FILE_TYPE = MACRO_DRAWING;
SET COLOR_WIRE YELLOW;
SET COLOR_PROP ORANGE;
SET COLOR_DOT WHITE;
SET COLOR_ARC YELLOW;
SET COLOR_BODY GREEN;
SET COLOR_NOTE PURPLE;
SET PROP_DISPLAY VALUE;
SET PAGE_NUMBER P333;
FORCEADD UNIVERSAL_GND..1
(-3525 7025);
FORCEPROP 3 LASTPIN (-3525 7075) SIG_NAME GND\g
J 0
(-3515 7085);
DISPLAY 0.659574 (-3515 7085);
PAINT MONO (-3515 7085);
DISPLAY INVISIBLE (-3515 7085);
FORCEPROP 2 LAST CDS_LIB pure_quanta_power
J 0
(-3525 7025);
DISPLAY INVISIBLE (-3525 7025);
FORCEPROP 1 LAST HDL_POWER GND
J 1
(-3500 6950);
DISPLAY 0.872340 (-3500 6950);
PAINT GREEN (-3500 6950);
DISPLAY INVISIBLE (-3500 6950);
FORCEPROP 1 LAST PATH I10
J 0
(-3450 7025);
DISPLAY 0.872340 (-3450 7025);
PAINT AQUA (-3450 7025);
DISPLAY INVISIBLE (-3450 7025);
FORCEADD MOSFET_NCH_DUAL..2
(1875 7800);
FORCEPROP 1 LAST LOCATION Q71
J 0
(2026 7776);
DISPLAY 0.723404 (2026 7776);
PAINT GREEN (2026 7776);
FORCEPROP 0 LAST $SEC 2
J 0
(2050 7925);
DISPLAY 0.680851 (2050 7925);
PAINT MONO (2050 7925);
DISPLAY INVISIBLE (2050 7925);
FORCEPROP 0 LAST CDS_SEC 2
J 0
(2050 7925);
DISPLAY 1.021277 (2050 7925);
DISPLAY INVISIBLE (2050 7925);
FORCEPROP 0 LASTPIN (1925 8000) $PN 3
R 1
J 0
(1915 8010);
DISPLAY 0.680851 (1915 8010);
PAINT MONO (1915 8010);
FORCEPROP 0 LASTPIN (1675 7750) $PN 5
J 2
(1665 7760);
DISPLAY 0.680851 (1665 7760);
PAINT MONO (1665 7760);
FORCEPROP 0 LASTPIN (1925 7600) $PN 4
R 1
J 2
(1915 7590);
DISPLAY 0.680851 (1915 7590);
PAINT MONO (1915 7590);
FORCEPROP 1 LAST MATERIAL IC
J 0
(2026 7651);
DISPLAY 0.723404 (2026 7651);
PAINT GREEN (2026 7651);
FORCEPROP 2 LAST VALUE PJT138K
J 0
(2050 7825);
DISPLAY 1.021277 (2050 7825);
FORCEPROP 2 LAST PART_TYPE SMLF
J 0
(2050 7875);
DISPLAY 1.021277 (2050 7875);
FORCEPROP 1 LAST CDS_LMAN_SYM_OUTLINE -150,150,150,-150
J 0
(1875 7800);
DISPLAY 0.468085 (1875 7800);
PAINT GREEN (1875 7800);
DISPLAY INVISIBLE (1875 7800);
FORCEPROP 1 LAST NEEDS_NO_SIZE TRUE
J 0
(2025 7691);
DISPLAY 0.468085 (2025 7691);
PAINT GREEN (2025 7691);
DISPLAY INVISIBLE (2025 7691);
FORCEPROP 2 LAST CDS_LIB pure_quanta
J 0
(1875 7800);
DISPLAY INVISIBLE (1875 7800);
FORCEPROP 1 LAST PATH I100
J 0
(2025 7650);
DISPLAY 0.723404 (2025 7650);
PAINT GREEN (2025 7650);
DISPLAY INVISIBLE (2025 7650);
FORCEPROP 1 LAST PART_NUMBER BAM138K0003
J 0
(2026 7706);
DISPLAY 0.723404 (2026 7706);
PAINT GREEN (2026 7706);
DISPLAY INVISIBLE (2026 7706);
FORCEADD Q_RES..2
(1925 8175);
FORCEPROP 1 LAST LOCATION R2934
J 0
(1970 8300);
DISPLAY 0.978723 (1970 8300);
FORCEPROP 0 LAST $SEC 1
J 0
(1975 8350);
DISPLAY 0.680851 (1975 8350);
PAINT MONO (1975 8350);
DISPLAY INVISIBLE (1975 8350);
FORCEPROP 0 LAST CDS_SEC 1
J 0
(1975 8350);
DISPLAY 1.021277 (1975 8350);
DISPLAY INVISIBLE (1975 8350);
FORCEPROP 1 LASTPIN (1925 8275) $PN 1
J 0
(1930 8237);
DISPLAY 0.787234 (1930 8237);
PAINT MONO (1930 8237);
FORCEPROP 1 LASTPIN (1925 8075) $PN 2
J 0
(1930 8085);
DISPLAY 0.787234 (1930 8085);
PAINT MONO (1930 8085);
FORCEPROP 1 LAST PACK_TYPE 0402LF
J 0
(1965 8050);
DISPLAY 0.638298 (1965 8050);
FORCEPROP 1 LAST WATTAGE 1/16W
J 0
(1965 8150);
DISPLAY 0.638298 (1965 8150);
FORCEPROP 1 LAST MATERIAL CHIP
J 0
(1965 8100);
DISPLAY 0.638298 (1965 8100);
FORCEPROP 1 LAST VALUE 100K
J 0
(1970 8250);
DISPLAY 0.638298 (1970 8250);
FORCEPROP 1 LAST TOLERANCE 1%
J 0
(1970 8200);
DISPLAY 0.638298 (1970 8200);
FORCEPROP 2 LAST CDS_LIB pure_quanta
J 0
(1925 8175);
DISPLAY INVISIBLE (1925 8175);
FORCEPROP 1 LAST PATH I101
J 0
(1975 8350);
DISPLAY 0.978723 (1975 8350);
PAINT WHITE (1975 8350);
DISPLAY INVISIBLE (1975 8350);
FORCEPROP 1 LAST PART_NUMBER CS41002FB09
J 0
(1965 8000);
DISPLAY 0.638298 (1965 8000);
DISPLAY INVISIBLE (1965 8000);
FORCEADD UNIVERSAL_POWER..1
(1925 8475);
FORCEPROP 3 LASTPIN (1925 8425) SIG_NAME P3V3_AUX\g
J 0
(1935 8435);
DISPLAY 0.659574 (1935 8435);
PAINT MONO (1935 8435);
DISPLAY INVISIBLE (1935 8435);
FORCEPROP 1 LAST HDL_POWER P3V3_AUX
J 1
(1925 8525);
DISPLAY 0.872340 (1925 8525);
PAINT GREEN (1925 8525);
FORCEPROP 2 LAST CDS_LIB pure_quanta_power
J 0
(1925 8475);
DISPLAY INVISIBLE (1925 8475);
FORCEPROP 1 LAST PATH I102
J 0
(1975 8500);
DISPLAY 0.872340 (1975 8500);
PAINT AQUA (1975 8500);
DISPLAY INVISIBLE (1975 8500);
FORCEADD UNIVERSAL_GND..1
(1925 7425);
FORCEPROP 3 LASTPIN (1925 7475) SIG_NAME GND\g
J 0
(1935 7485);
DISPLAY 0.659574 (1935 7485);
PAINT MONO (1935 7485);
DISPLAY INVISIBLE (1935 7485);
FORCEPROP 2 LAST CDS_LIB pure_quanta_power
J 0
(1925 7425);
DISPLAY INVISIBLE (1925 7425);
FORCEPROP 1 LAST HDL_POWER GND
J 1
(1950 7350);
DISPLAY 0.872340 (1950 7350);
PAINT GREEN (1950 7350);
DISPLAY INVISIBLE (1950 7350);
FORCEPROP 1 LAST PATH I103
J 0
(2000 7425);
DISPLAY 0.872340 (2000 7425);
PAINT AQUA (2000 7425);
DISPLAY INVISIBLE (2000 7425);
FORCEADD UNIVERSAL_GND..1
(2925 6050);
FORCEPROP 3 LASTPIN (2925 6100) SIG_NAME GND\g
J 0
(2935 6110);
DISPLAY 0.659574 (2935 6110);
PAINT MONO (2935 6110);
DISPLAY INVISIBLE (2935 6110);
FORCEPROP 2 LAST CDS_LIB pure_quanta_power
J 0
(2925 6050);
DISPLAY INVISIBLE (2925 6050);
FORCEPROP 1 LAST HDL_POWER GND
J 1
(2950 5975);
DISPLAY 0.872340 (2950 5975);
PAINT GREEN (2950 5975);
DISPLAY INVISIBLE (2950 5975);
FORCEPROP 1 LAST PATH I104
J 0
(3000 6050);
DISPLAY 0.872340 (3000 6050);
PAINT AQUA (3000 6050);
DISPLAY INVISIBLE (3000 6050);
FORCEADD Q_CAP..1
(2925 6250);
FORCEPROP 1 LAST LOCATION C1756
J 0
(2975 6350);
DISPLAY 0.638298 (2975 6350);
FORCEPROP 2 LAST $SEC 1
J 0
(2975 6450);
DISPLAY 0.680851 (2975 6450);
PAINT MONO (2975 6450);
DISPLAY INVISIBLE (2975 6450);
FORCEPROP 2 LAST CDS_SEC 1
J 0
(2975 6450);
DISPLAY 1.021277 (2975 6450);
DISPLAY INVISIBLE (2975 6450);
FORCEPROP 1 LASTPIN (2925 6350) $PN 1
J 0
(2935 6330);
DISPLAY 0.787234 (2935 6330);
PAINT MONO (2935 6330);
FORCEPROP 1 LASTPIN (2925 6150) $PN 2
J 0
(2935 6130);
DISPLAY 0.787234 (2935 6130);
PAINT MONO (2935 6130);
FORCEPROP 1 LAST VALUE 0.1UF
J 0
(2975 6300);
DISPLAY 0.638298 (2975 6300);
FORCEPROP 1 LAST VOLTAGE 25V
J 0
(2975 6250);
DISPLAY 0.638298 (2975 6250);
FORCEPROP 1 LAST TOLERANCE 10%
J 0
(2975 6200);
DISPLAY 0.638298 (2975 6200);
FORCEPROP 1 LAST MATERIAL X7R
J 0
(2975 6150);
DISPLAY 0.638298 (2975 6150);
PAINT RED (2975 6150);
FORCEPROP 1 LAST PACK_TYPE 0402
J 0
(2975 6050);
DISPLAY 0.638298 (2975 6050);
FORCEPROP 2 LAST CDS_LIB pure_quanta
J 0
(2925 6250);
DISPLAY INVISIBLE (2925 6250);
FORCEPROP 1 LAST PATH I105
J 0
(2975 6400);
DISPLAY 0.978723 (2975 6400);
PAINT WHITE (2975 6400);
DISPLAY INVISIBLE (2975 6400);
FORCEPROP 1 LAST PART_NUMBER CH4104K1B00
J 0
(2975 6100);
DISPLAY 0.638298 (2975 6100);
DISPLAY INVISIBLE (2975 6100);
FORCEADD OFFPAGE..2
(3200 6650);
FORCEPROP 2 LAST $XR0 81 
J 0
(3389 6650);
DISPLAY 0.638298 (3389 6650);
PAINT MONO (3389 6650);
FORCEPROP 2 LAST CDS_LIB standard
J 0
(3200 6650);
DISPLAY INVISIBLE (3200 6650);
FORCEPROP 1 LAST OFFPAGE TRUE
J 0
(3525 6525);
DISPLAY 0.872340 (3525 6525);
PAINT AQUA (3525 6525);
DISPLAY INVISIBLE (3525 6525);
FORCEPROP 1 LAST COMMENT_BODY TRUE
J 0
(3155 6555);
DISPLAY 0.872340 (3155 6555);
PAINT GREEN (3155 6555);
DISPLAY INVISIBLE (3155 6555);
FORCEPROP 2 LAST PATH I106
J 0
(3400 6700);
DISPLAY 1.021277 (3400 6700);
DISPLAY INVISIBLE (3400 6700);
FORCEADD UNIVERSAL_GND..1
(2025 6050);
FORCEPROP 3 LASTPIN (2025 6100) SIG_NAME GND\g
J 0
(2035 6110);
DISPLAY 0.659574 (2035 6110);
PAINT MONO (2035 6110);
DISPLAY INVISIBLE (2035 6110);
FORCEPROP 2 LAST CDS_LIB pure_quanta_power
J 0
(2025 6050);
DISPLAY INVISIBLE (2025 6050);
FORCEPROP 1 LAST HDL_POWER GND
J 1
(2050 5975);
DISPLAY 0.872340 (2050 5975);
PAINT GREEN (2050 5975);
DISPLAY INVISIBLE (2050 5975);
FORCEPROP 1 LAST PATH I108
J 0
(2100 6050);
DISPLAY 0.872340 (2100 6050);
PAINT AQUA (2100 6050);
DISPLAY INVISIBLE (2100 6050);
FORCEADD Q_RES..2
(2025 6875);
FORCEPROP 1 LAST LOCATION R2935
J 0
(2070 7000);
DISPLAY 0.978723 (2070 7000);
FORCEPROP 0 LAST $SEC 1
J 0
(2075 7050);
DISPLAY 0.680851 (2075 7050);
PAINT MONO (2075 7050);
DISPLAY INVISIBLE (2075 7050);
FORCEPROP 0 LAST CDS_SEC 1
J 0
(2075 7050);
DISPLAY 1.021277 (2075 7050);
DISPLAY INVISIBLE (2075 7050);
FORCEPROP 1 LASTPIN (2025 6975) $PN 1
J 0
(2030 6937);
DISPLAY 0.787234 (2030 6937);
PAINT MONO (2030 6937);
FORCEPROP 1 LASTPIN (2025 6775) $PN 2
J 0
(2030 6785);
DISPLAY 0.787234 (2030 6785);
PAINT MONO (2030 6785);
FORCEPROP 1 LAST PACK_TYPE 0402LF
J 0
(2065 6750);
DISPLAY 0.638298 (2065 6750);
FORCEPROP 1 LAST WATTAGE 1/16W
J 0
(2065 6850);
DISPLAY 0.638298 (2065 6850);
FORCEPROP 1 LAST MATERIAL CHIP
J 0
(2065 6800);
DISPLAY 0.638298 (2065 6800);
FORCEPROP 1 LAST VALUE 100K
J 0
(2070 6950);
DISPLAY 0.638298 (2070 6950);
FORCEPROP 1 LAST TOLERANCE 1%
J 0
(2070 6900);
DISPLAY 0.638298 (2070 6900);
FORCEPROP 2 LAST CDS_LIB pure_quanta
J 0
(2025 6875);
DISPLAY INVISIBLE (2025 6875);
FORCEPROP 1 LAST PATH I109
J 0
(2075 7050);
DISPLAY 0.978723 (2075 7050);
PAINT WHITE (2075 7050);
DISPLAY INVISIBLE (2075 7050);
FORCEPROP 1 LAST PART_NUMBER CS41002FB09
J 0
(2065 6700);
DISPLAY 0.638298 (2065 6700);
DISPLAY INVISIBLE (2065 6700);
FORCEADD UNIVERSAL_GND..1
(-3475 5625);
FORCEPROP 3 LASTPIN (-3475 5675) SIG_NAME GND\g
J 0
(-3465 5685);
DISPLAY 0.659574 (-3465 5685);
PAINT MONO (-3465 5685);
DISPLAY INVISIBLE (-3465 5685);
FORCEPROP 2 LAST CDS_LIB pure_quanta_power
J 0
(-3475 5625);
DISPLAY INVISIBLE (-3475 5625);
FORCEPROP 1 LAST HDL_POWER GND
J 1
(-3450 5550);
DISPLAY 0.872340 (-3450 5550);
PAINT GREEN (-3450 5550);
DISPLAY INVISIBLE (-3450 5550);
FORCEPROP 1 LAST PATH I11
J 0
(-3400 5625);
DISPLAY 0.872340 (-3400 5625);
PAINT AQUA (-3400 5625);
DISPLAY INVISIBLE (-3400 5625);
FORCEADD UNIVERSAL_POWER..1
(2025 7175);
FORCEPROP 3 LASTPIN (2025 7125) SIG_NAME P3V3_AUX\g
J 0
(2035 7135);
DISPLAY 0.659574 (2035 7135);
PAINT MONO (2035 7135);
DISPLAY INVISIBLE (2035 7135);
FORCEPROP 1 LAST HDL_POWER P3V3_AUX
J 1
(2025 7225);
DISPLAY 0.872340 (2025 7225);
PAINT GREEN (2025 7225);
FORCEPROP 2 LAST CDS_LIB pure_quanta_power
J 0
(2025 7175);
DISPLAY INVISIBLE (2025 7175);
FORCEPROP 1 LAST PATH I110
J 0
(2075 7200);
DISPLAY 0.872340 (2075 7200);
PAINT AQUA (2075 7200);
DISPLAY INVISIBLE (2075 7200);
FORCEADD Q_CAP..1
(2875 7775);
FORCEPROP 1 LAST LOCATION C1774
J 0
(2925 7875);
DISPLAY 0.978723 (2925 7875);
FORCEPROP 0 LAST $SEC 1
J 0
(2925 7925);
DISPLAY 0.680851 (2925 7925);
PAINT MONO (2925 7925);
DISPLAY INVISIBLE (2925 7925);
FORCEPROP 0 LAST CDS_SEC 1
J 0
(2925 7925);
DISPLAY 1.021277 (2925 7925);
DISPLAY INVISIBLE (2925 7925);
FORCEPROP 1 LASTPIN (2875 7875) $PN 1
J 0
(2885 7855);
DISPLAY 0.787234 (2885 7855);
PAINT MONO (2885 7855);
FORCEPROP 1 LASTPIN (2875 7675) $PN 2
J 0
(2885 7655);
DISPLAY 0.787234 (2885 7655);
PAINT MONO (2885 7655);
FORCEPROP 1 LAST VOLTAGE 25V
J 0
(2925 7775);
DISPLAY 0.638298 (2925 7775);
FORCEPROP 1 LAST VALUE 0.1UF
J 0
(2925 7825);
DISPLAY 0.638298 (2925 7825);
FORCEPROP 1 LAST TOLERANCE 10%
J 0
(2925 7725);
DISPLAY 0.638298 (2925 7725);
FORCEPROP 1 LAST MATERIAL X7R
J 0
(2925 7675);
DISPLAY 0.638298 (2925 7675);
PAINT RED (2925 7675);
FORCEPROP 1 LAST PACK_TYPE 0402
J 0
(2925 7575);
DISPLAY 0.638298 (2925 7575);
FORCEPROP 2 LAST CDS_LIB pure_quanta
J 0
(2875 7775);
DISPLAY INVISIBLE (2875 7775);
FORCEPROP 1 LAST PATH I111
J 0
(2925 7925);
DISPLAY 0.978723 (2925 7925);
PAINT WHITE (2925 7925);
DISPLAY INVISIBLE (2925 7925);
FORCEPROP 1 LAST PART_NUMBER CH4104K1B00
J 0
(2925 7625);
DISPLAY 0.638298 (2925 7625);
DISPLAY INVISIBLE (2925 7625);
FORCEADD UNIVERSAL_GND..1
(2875 7575);
FORCEPROP 3 LASTPIN (2875 7625) SIG_NAME GND\g
J 0
(2885 7635);
DISPLAY 0.659574 (2885 7635);
PAINT MONO (2885 7635);
DISPLAY INVISIBLE (2885 7635);
FORCEPROP 2 LAST CDS_LIB pure_quanta_power
J 0
(2875 7575);
DISPLAY INVISIBLE (2875 7575);
FORCEPROP 1 LAST HDL_POWER GND
J 1
(2900 7500);
DISPLAY 0.872340 (2900 7500);
PAINT GREEN (2900 7500);
DISPLAY INVISIBLE (2900 7500);
FORCEPROP 1 LAST PATH I112
J 0
(2950 7575);
DISPLAY 0.872340 (2950 7575);
PAINT AQUA (2950 7575);
DISPLAY INVISIBLE (2950 7575);
FORCEADD UNIVERSAL_GND..1
(-1600 7450);
FORCEPROP 3 LASTPIN (-1600 7500) SIG_NAME GND\g
J 0
(-1590 7510);
DISPLAY 0.659574 (-1590 7510);
PAINT MONO (-1590 7510);
DISPLAY INVISIBLE (-1590 7510);
FORCEPROP 2 LAST CDS_LIB pure_quanta_power
J 0
(-1600 7450);
DISPLAY INVISIBLE (-1600 7450);
FORCEPROP 1 LAST HDL_POWER GND
J 1
(-1575 7375);
DISPLAY 0.872340 (-1575 7375);
PAINT GREEN (-1575 7375);
DISPLAY INVISIBLE (-1575 7375);
FORCEPROP 1 LAST PATH I113
J 0
(-1525 7450);
DISPLAY 0.872340 (-1525 7450);
PAINT AQUA (-1525 7450);
DISPLAY INVISIBLE (-1525 7450);
FORCEADD Q_CAP..1
(-1600 7650);
FORCEPROP 1 LAST LOCATION C1773
J 0
(-1550 7750);
DISPLAY 0.978723 (-1550 7750);
FORCEPROP 0 LAST $SEC 1
J 0
(-1550 7800);
DISPLAY 0.680851 (-1550 7800);
PAINT MONO (-1550 7800);
DISPLAY INVISIBLE (-1550 7800);
FORCEPROP 0 LAST CDS_SEC 1
J 0
(-1550 7800);
DISPLAY 1.021277 (-1550 7800);
DISPLAY INVISIBLE (-1550 7800);
FORCEPROP 1 LASTPIN (-1600 7750) $PN 1
J 0
(-1590 7730);
DISPLAY 0.787234 (-1590 7730);
PAINT MONO (-1590 7730);
FORCEPROP 1 LASTPIN (-1600 7550) $PN 2
J 0
(-1590 7530);
DISPLAY 0.787234 (-1590 7530);
PAINT MONO (-1590 7530);
FORCEPROP 1 LAST PACK_TYPE 0402
J 0
(-1550 7450);
DISPLAY 0.638298 (-1550 7450);
FORCEPROP 1 LAST MATERIAL X7R
J 0
(-1550 7550);
DISPLAY 0.638298 (-1550 7550);
PAINT RED (-1550 7550);
FORCEPROP 1 LAST TOLERANCE 10%
J 0
(-1550 7600);
DISPLAY 0.638298 (-1550 7600);
FORCEPROP 1 LAST VOLTAGE 25V
J 0
(-1550 7650);
DISPLAY 0.638298 (-1550 7650);
FORCEPROP 1 LAST VALUE 0.1UF
J 0
(-1550 7700);
DISPLAY 0.638298 (-1550 7700);
FORCEPROP 2 LAST CDS_LIB pure_quanta
J 0
(-1600 7650);
DISPLAY INVISIBLE (-1600 7650);
FORCEPROP 1 LAST PATH I114
J 0
(-1550 7800);
DISPLAY 0.978723 (-1550 7800);
PAINT WHITE (-1550 7800);
DISPLAY INVISIBLE (-1550 7800);
FORCEPROP 1 LAST PART_NUMBER CH4104K1B00
J 0
(-1550 7500);
DISPLAY 0.638298 (-1550 7500);
DISPLAY INVISIBLE (-1550 7500);
FORCEADD UNIVERSAL_GND..1
(-1650 6075);
FORCEPROP 3 LASTPIN (-1650 6125) SIG_NAME GND\g
J 0
(-1640 6135);
DISPLAY 0.659574 (-1640 6135);
PAINT MONO (-1640 6135);
DISPLAY INVISIBLE (-1640 6135);
FORCEPROP 2 LAST CDS_LIB pure_quanta_power
J 0
(-1650 6075);
DISPLAY INVISIBLE (-1650 6075);
FORCEPROP 1 LAST HDL_POWER GND
J 1
(-1625 6000);
DISPLAY 0.872340 (-1625 6000);
PAINT GREEN (-1625 6000);
DISPLAY INVISIBLE (-1625 6000);
FORCEPROP 1 LAST PATH I115
J 0
(-1575 6075);
DISPLAY 0.872340 (-1575 6075);
PAINT AQUA (-1575 6075);
DISPLAY INVISIBLE (-1575 6075);
FORCEADD Q_CAP..1
(-1650 6275);
FORCEPROP 1 LAST LOCATION C1772
J 0
(-1600 6375);
DISPLAY 0.978723 (-1600 6375);
FORCEPROP 0 LAST $SEC 1
J 0
(-1600 6425);
DISPLAY 0.680851 (-1600 6425);
PAINT MONO (-1600 6425);
DISPLAY INVISIBLE (-1600 6425);
FORCEPROP 0 LAST CDS_SEC 1
J 0
(-1600 6425);
DISPLAY 1.021277 (-1600 6425);
DISPLAY INVISIBLE (-1600 6425);
FORCEPROP 1 LASTPIN (-1650 6375) $PN 1
J 0
(-1640 6355);
DISPLAY 0.787234 (-1640 6355);
PAINT MONO (-1640 6355);
FORCEPROP 1 LASTPIN (-1650 6175) $PN 2
J 0
(-1640 6155);
DISPLAY 0.787234 (-1640 6155);
PAINT MONO (-1640 6155);
FORCEPROP 1 LAST VALUE 0.1UF
J 0
(-1600 6325);
DISPLAY 0.638298 (-1600 6325);
FORCEPROP 1 LAST VOLTAGE 25V
J 0
(-1600 6275);
DISPLAY 0.638298 (-1600 6275);
FORCEPROP 1 LAST MATERIAL X7R
J 0
(-1600 6175);
DISPLAY 0.638298 (-1600 6175);
PAINT RED (-1600 6175);
FORCEPROP 1 LAST PACK_TYPE 0402
J 0
(-1600 6075);
DISPLAY 0.638298 (-1600 6075);
FORCEPROP 1 LAST TOLERANCE 10%
J 0
(-1600 6225);
DISPLAY 0.638298 (-1600 6225);
FORCEPROP 2 LAST CDS_LIB pure_quanta
J 0
(-1650 6275);
DISPLAY INVISIBLE (-1650 6275);
FORCEPROP 1 LAST PATH I116
J 0
(-1600 6425);
DISPLAY 0.978723 (-1600 6425);
PAINT WHITE (-1600 6425);
DISPLAY INVISIBLE (-1600 6425);
FORCEPROP 1 LAST PART_NUMBER CH4104K1B00
J 0
(-1600 6125);
DISPLAY 0.638298 (-1600 6125);
DISPLAY INVISIBLE (-1600 6125);
FORCEADD MOSFET_NCH_DUAL..1
(-3525 6000);
FORCEPROP 1 LAST LOCATION Q69
J 0
(-3374 5974);
DISPLAY 0.723404 (-3374 5974);
PAINT GREEN (-3374 5974);
FORCEPROP 0 LAST $SEC 1
J 0
(-3350 6125);
DISPLAY 0.680851 (-3350 6125);
PAINT MONO (-3350 6125);
DISPLAY INVISIBLE (-3350 6125);
FORCEPROP 0 LAST CDS_SEC 1
J 0
(-3350 6125);
DISPLAY 1.021277 (-3350 6125);
DISPLAY INVISIBLE (-3350 6125);
FORCEPROP 0 LASTPIN (-3475 6200) $PN 6
R 1
J 0
(-3485 6210);
DISPLAY 0.680851 (-3485 6210);
PAINT MONO (-3485 6210);
FORCEPROP 0 LASTPIN (-3725 5950) $PN 2
J 2
(-3735 5960);
DISPLAY 0.680851 (-3735 5960);
PAINT MONO (-3735 5960);
FORCEPROP 0 LASTPIN (-3475 5800) $PN 1
R 1
J 2
(-3485 5790);
DISPLAY 0.680851 (-3485 5790);
PAINT MONO (-3485 5790);
FORCEPROP 2 LAST VALUE PJT138K
J 0
(-3350 6025);
DISPLAY 1.021277 (-3350 6025);
FORCEPROP 2 LAST PART_TYPE SMLF
J 0
(-3350 6075);
DISPLAY 1.021277 (-3350 6075);
FORCEPROP 1 LAST MATERIAL IC
J 0
(-3374 5849);
DISPLAY 0.723404 (-3374 5849);
PAINT GREEN (-3374 5849);
FORCEPROP 1 LAST CDS_LMAN_SYM_OUTLINE -150,150,150,-150
J 0
(-3525 6000);
DISPLAY 0.468085 (-3525 6000);
PAINT GREEN (-3525 6000);
DISPLAY INVISIBLE (-3525 6000);
FORCEPROP 1 LAST NEEDS_NO_SIZE TRUE
J 0
(-3525 5999);
DISPLAY 0.468085 (-3525 5999);
PAINT GREEN (-3525 5999);
DISPLAY INVISIBLE (-3525 5999);
FORCEPROP 2 LAST CDS_LIB pure_quanta
J 0
(-3525 6000);
DISPLAY INVISIBLE (-3525 6000);
FORCEPROP 1 LAST PATH I117
J 0
(-3525 6000);
DISPLAY 0.723404 (-3525 6000);
PAINT GREEN (-3525 6000);
DISPLAY INVISIBLE (-3525 6000);
FORCEPROP 1 LAST PART_NUMBER BAM138K0003
J 0
(-3374 5914);
DISPLAY 0.723404 (-3374 5914);
PAINT GREEN (-3374 5914);
DISPLAY INVISIBLE (-3374 5914);
FORCEADD MOSFET_NCH_DUAL..1
(1050 7525);
FORCEPROP 1 LAST LOCATION Q71
J 0
(1201 7499);
DISPLAY 0.723404 (1201 7499);
PAINT GREEN (1201 7499);
FORCEPROP 0 LAST $SEC 1
J 0
(1225 7650);
DISPLAY 0.680851 (1225 7650);
PAINT MONO (1225 7650);
DISPLAY INVISIBLE (1225 7650);
FORCEPROP 0 LAST CDS_SEC 1
J 0
(1225 7650);
DISPLAY 1.021277 (1225 7650);
DISPLAY INVISIBLE (1225 7650);
FORCEPROP 0 LASTPIN (1100 7725) $PN 6
R 1
J 0
(1090 7735);
DISPLAY 0.680851 (1090 7735);
PAINT MONO (1090 7735);
FORCEPROP 0 LASTPIN (850 7475) $PN 2
J 2
(840 7485);
DISPLAY 0.680851 (840 7485);
PAINT MONO (840 7485);
FORCEPROP 0 LASTPIN (1100 7325) $PN 1
R 1
J 2
(1090 7315);
DISPLAY 0.680851 (1090 7315);
PAINT MONO (1090 7315);
FORCEPROP 1 LAST MATERIAL IC
J 0
(1201 7374);
DISPLAY 0.723404 (1201 7374);
PAINT GREEN (1201 7374);
FORCEPROP 2 LAST PART_TYPE SMLF
J 0
(1225 7600);
DISPLAY 1.021277 (1225 7600);
FORCEPROP 2 LAST VALUE PJT138K
J 0
(1225 7550);
DISPLAY 1.021277 (1225 7550);
FORCEPROP 1 LAST CDS_LMAN_SYM_OUTLINE -150,150,150,-150
J 0
(1050 7525);
DISPLAY 0.468085 (1050 7525);
PAINT GREEN (1050 7525);
DISPLAY INVISIBLE (1050 7525);
FORCEPROP 1 LAST NEEDS_NO_SIZE TRUE
J 0
(1050 7524);
DISPLAY 0.468085 (1050 7524);
PAINT GREEN (1050 7524);
DISPLAY INVISIBLE (1050 7524);
FORCEPROP 2 LAST CDS_LIB pure_quanta
J 0
(1050 7525);
DISPLAY INVISIBLE (1050 7525);
FORCEPROP 1 LAST PATH I118
J 0
(1050 7525);
DISPLAY 0.723404 (1050 7525);
PAINT GREEN (1050 7525);
DISPLAY INVISIBLE (1050 7525);
FORCEPROP 1 LAST PART_NUMBER BAM138K0003
J 0
(1201 7439);
DISPLAY 0.723404 (1201 7439);
PAINT GREEN (1201 7439);
DISPLAY INVISIBLE (1201 7439);
FORCEADD MOSFET_NCH_DUAL..2
(1975 6425);
FORCEPROP 1 LAST LOCATION Q72
J 0
(2126 6401);
DISPLAY 0.723404 (2126 6401);
PAINT GREEN (2126 6401);
FORCEPROP 2 LAST SEC 2
J 0
(2150 6550);
DISPLAY 0.680851 (2150 6550);
PAINT MONO (2150 6550);
DISPLAY INVISIBLE (2150 6550);
FORCEPROP 2 LASTPIN (2025 6625) $PN 3
R 1
J 0
(2015 6635);
DISPLAY 0.680851 (2015 6635);
PAINT MONO (2015 6635);
FORCEPROP 2 LASTPIN (1775 6375) $PN 5
J 2
(1765 6385);
DISPLAY 0.680851 (1765 6385);
PAINT MONO (1765 6385);
FORCEPROP 2 LASTPIN (2025 6225) $PN 4
R 1
J 2
(2015 6215);
DISPLAY 0.680851 (2015 6215);
PAINT MONO (2015 6215);
FORCEPROP 2 LAST PART_TYPE SMLF
J 0
(2150 6500);
DISPLAY 1.021277 (2150 6500);
FORCEPROP 1 LAST MATERIAL IC
J 0
(2126 6276);
DISPLAY 0.723404 (2126 6276);
PAINT GREEN (2126 6276);
FORCEPROP 2 LAST VALUE PJT138K
J 0
(2150 6450);
DISPLAY 1.021277 (2150 6450);
FORCEPROP 1 LAST CDS_LMAN_SYM_OUTLINE -150,150,150,-150
J 0
(1975 6425);
DISPLAY 0.468085 (1975 6425);
PAINT GREEN (1975 6425);
DISPLAY INVISIBLE (1975 6425);
FORCEPROP 1 LAST NEEDS_NO_SIZE TRUE
J 0
(2125 6316);
DISPLAY 0.468085 (2125 6316);
PAINT GREEN (2125 6316);
DISPLAY INVISIBLE (2125 6316);
FORCEPROP 2 LAST CDS_LIB pure_quanta
J 0
(1975 6425);
DISPLAY INVISIBLE (1975 6425);
FORCEPROP 2 LAST SEC_TYPE 
J 0
(2150 6550);
DISPLAY 1.021277 (2150 6550);
DISPLAY INVISIBLE (2150 6550);
FORCEPROP 1 LAST PATH I119
J 0
(2125 6275);
DISPLAY 0.723404 (2125 6275);
PAINT GREEN (2125 6275);
DISPLAY INVISIBLE (2125 6275);
FORCEPROP 1 LAST PART_NUMBER BAM138K0003
J 0
(2126 6331);
DISPLAY 0.723404 (2126 6331);
PAINT GREEN (2126 6331);
DISPLAY INVISIBLE (2126 6331);
FORCEADD UNIVERSAL_GND..1
(-3450 4275);
FORCEPROP 3 LASTPIN (-3450 4325) SIG_NAME GND\g
J 0
(-3440 4335);
DISPLAY 0.659574 (-3440 4335);
PAINT MONO (-3440 4335);
DISPLAY INVISIBLE (-3440 4335);
FORCEPROP 2 LAST CDS_LIB pure_quanta_power
J 0
(-3450 4275);
DISPLAY INVISIBLE (-3450 4275);
FORCEPROP 1 LAST HDL_POWER GND
J 1
(-3425 4200);
DISPLAY 0.872340 (-3425 4200);
PAINT GREEN (-3425 4200);
DISPLAY INVISIBLE (-3425 4200);
FORCEPROP 1 LAST PATH I12
J 0
(-3375 4275);
DISPLAY 0.872340 (-3375 4275);
PAINT AQUA (-3375 4275);
DISPLAY INVISIBLE (-3375 4275);
FORCEADD MOSFET_NCH_DUAL..2
(-2550 4925);
FORCEPROP 1 LAST LOCATION Q70
J 0
(-2399 4901);
DISPLAY 0.723404 (-2399 4901);
PAINT GREEN (-2399 4901);
FORCEPROP 0 LAST $SEC 2
J 0
(-2375 5050);
DISPLAY 0.680851 (-2375 5050);
PAINT MONO (-2375 5050);
DISPLAY INVISIBLE (-2375 5050);
FORCEPROP 0 LAST CDS_SEC 2
J 0
(-2375 5050);
DISPLAY 1.021277 (-2375 5050);
DISPLAY INVISIBLE (-2375 5050);
FORCEPROP 0 LASTPIN (-2500 5125) $PN 3
R 1
J 0
(-2510 5135);
DISPLAY 0.680851 (-2510 5135);
PAINT MONO (-2510 5135);
FORCEPROP 0 LASTPIN (-2750 4875) $PN 5
J 2
(-2760 4885);
DISPLAY 0.680851 (-2760 4885);
PAINT MONO (-2760 4885);
FORCEPROP 0 LASTPIN (-2500 4725) $PN 4
R 1
J 2
(-2510 4715);
DISPLAY 0.680851 (-2510 4715);
PAINT MONO (-2510 4715);
FORCEPROP 2 LAST PART_TYPE SMLF
J 0
(-2375 5000);
DISPLAY 1.021277 (-2375 5000);
FORCEPROP 2 LAST VALUE PJT138K
J 0
(-2375 4950);
DISPLAY 1.021277 (-2375 4950);
FORCEPROP 1 LAST MATERIAL IC
J 0
(-2399 4776);
DISPLAY 0.723404 (-2399 4776);
PAINT GREEN (-2399 4776);
FORCEPROP 1 LAST CDS_LMAN_SYM_OUTLINE -150,150,150,-150
J 0
(-2550 4925);
DISPLAY 0.468085 (-2550 4925);
PAINT GREEN (-2550 4925);
DISPLAY INVISIBLE (-2550 4925);
FORCEPROP 1 LAST NEEDS_NO_SIZE TRUE
J 0
(-2400 4816);
DISPLAY 0.468085 (-2400 4816);
PAINT GREEN (-2400 4816);
DISPLAY INVISIBLE (-2400 4816);
FORCEPROP 2 LAST CDS_LIB pure_quanta
J 0
(-2550 4925);
DISPLAY INVISIBLE (-2550 4925);
FORCEPROP 1 LAST PATH I120
J 0
(-2400 4775);
DISPLAY 0.723404 (-2400 4775);
PAINT GREEN (-2400 4775);
DISPLAY INVISIBLE (-2400 4775);
FORCEPROP 1 LAST PART_NUMBER BAM138K0003
J 0
(-2399 4831);
DISPLAY 0.723404 (-2399 4831);
PAINT GREEN (-2399 4831);
DISPLAY INVISIBLE (-2399 4831);
FORCEADD MOSFET_NCH_DUAL..1
(1075 4775);
FORCEPROP 1 LAST LOCATION Q74
J 0
(1226 4749);
DISPLAY 0.723404 (1226 4749);
PAINT GREEN (1226 4749);
FORCEPROP 2 LAST SEC 1
J 0
(1250 4900);
DISPLAY 0.680851 (1250 4900);
PAINT MONO (1250 4900);
DISPLAY INVISIBLE (1250 4900);
FORCEPROP 2 LASTPIN (1125 4975) $PN 6
R 1
J 0
(1115 4985);
DISPLAY 0.680851 (1115 4985);
PAINT MONO (1115 4985);
FORCEPROP 2 LASTPIN (875 4725) $PN 2
J 2
(865 4735);
DISPLAY 0.680851 (865 4735);
PAINT MONO (865 4735);
FORCEPROP 2 LASTPIN (1125 4575) $PN 1
R 1
J 2
(1115 4565);
DISPLAY 0.680851 (1115 4565);
PAINT MONO (1115 4565);
FORCEPROP 2 LAST VALUE PJT138K
J 0
(1250 4800);
DISPLAY 1.021277 (1250 4800);
FORCEPROP 1 LAST MATERIAL IC
J 0
(1226 4624);
DISPLAY 0.723404 (1226 4624);
PAINT GREEN (1226 4624);
FORCEPROP 2 LAST PART_TYPE SMLF
J 0
(1250 4850);
DISPLAY 1.021277 (1250 4850);
FORCEPROP 1 LAST CDS_LMAN_SYM_OUTLINE -150,150,150,-150
J 0
(1075 4775);
DISPLAY 0.468085 (1075 4775);
PAINT GREEN (1075 4775);
DISPLAY INVISIBLE (1075 4775);
FORCEPROP 1 LAST NEEDS_NO_SIZE TRUE
J 0
(1075 4774);
DISPLAY 0.468085 (1075 4774);
PAINT GREEN (1075 4774);
DISPLAY INVISIBLE (1075 4774);
FORCEPROP 2 LAST CDS_LIB pure_quanta
J 0
(1075 4775);
DISPLAY INVISIBLE (1075 4775);
FORCEPROP 2 LAST SEC_TYPE 
J 0
(1250 4900);
DISPLAY 1.021277 (1250 4900);
DISPLAY INVISIBLE (1250 4900);
FORCEPROP 1 LAST PATH I121
J 0
(1075 4775);
DISPLAY 0.723404 (1075 4775);
PAINT GREEN (1075 4775);
DISPLAY INVISIBLE (1075 4775);
FORCEPROP 1 LAST PART_NUMBER BAM138K0003
J 0
(1226 4689);
DISPLAY 0.723404 (1226 4689);
PAINT GREEN (1226 4689);
DISPLAY INVISIBLE (1226 4689);
FORCEADD MOSFET_NCH_DUAL..2
(2000 5050);
FORCEPROP 1 LAST LOCATION Q74
J 0
(2151 5026);
DISPLAY 0.723404 (2151 5026);
PAINT GREEN (2151 5026);
FORCEPROP 2 LAST SEC 2
J 0
(2175 5175);
DISPLAY 0.680851 (2175 5175);
PAINT MONO (2175 5175);
DISPLAY INVISIBLE (2175 5175);
FORCEPROP 2 LASTPIN (2050 5250) $PN 3
R 1
J 0
(2040 5260);
DISPLAY 0.680851 (2040 5260);
PAINT MONO (2040 5260);
FORCEPROP 2 LASTPIN (1800 5000) $PN 5
J 2
(1790 5010);
DISPLAY 0.680851 (1790 5010);
PAINT MONO (1790 5010);
FORCEPROP 2 LASTPIN (2050 4850) $PN 4
R 1
J 2
(2040 4840);
DISPLAY 0.680851 (2040 4840);
PAINT MONO (2040 4840);
FORCEPROP 1 LAST MATERIAL IC
J 0
(2151 4901);
DISPLAY 0.723404 (2151 4901);
PAINT GREEN (2151 4901);
FORCEPROP 2 LAST VALUE PJT138K
J 0
(2175 5075);
DISPLAY 1.021277 (2175 5075);
FORCEPROP 2 LAST PART_TYPE SMLF
J 0
(2175 5125);
DISPLAY 1.021277 (2175 5125);
FORCEPROP 1 LAST NEEDS_NO_SIZE TRUE
J 0
(2150 4941);
DISPLAY 0.468085 (2150 4941);
PAINT GREEN (2150 4941);
DISPLAY INVISIBLE (2150 4941);
FORCEPROP 1 LAST CDS_LMAN_SYM_OUTLINE -150,150,150,-150
J 0
(2000 5050);
DISPLAY 0.468085 (2000 5050);
PAINT GREEN (2000 5050);
DISPLAY INVISIBLE (2000 5050);
FORCEPROP 2 LAST CDS_LIB pure_quanta
J 0
(2000 5050);
DISPLAY INVISIBLE (2000 5050);
FORCEPROP 2 LAST SEC_TYPE 
J 0
(2175 5175);
DISPLAY 1.021277 (2175 5175);
DISPLAY INVISIBLE (2175 5175);
FORCEPROP 1 LAST PATH I122
J 0
(2150 4900);
DISPLAY 0.723404 (2150 4900);
PAINT GREEN (2150 4900);
DISPLAY INVISIBLE (2150 4900);
FORCEPROP 1 LAST PART_NUMBER BAM138K0003
J 0
(2151 4956);
DISPLAY 0.723404 (2151 4956);
PAINT GREEN (2151 4956);
DISPLAY INVISIBLE (2151 4956);
FORCEADD UNIVERSAL_POWER..1
(2050 5800);
FORCEPROP 3 LASTPIN (2050 5750) SIG_NAME P3V3_AUX\g
J 0
(2060 5760);
DISPLAY 0.659574 (2060 5760);
PAINT MONO (2060 5760);
DISPLAY INVISIBLE (2060 5760);
FORCEPROP 1 LAST HDL_POWER P3V3_AUX
J 1
(2050 5850);
DISPLAY 0.872340 (2050 5850);
PAINT GREEN (2050 5850);
FORCEPROP 2 LAST CDS_LIB pure_quanta_power
J 0
(2050 5800);
DISPLAY INVISIBLE (2050 5800);
FORCEPROP 1 LAST PATH I123
J 0
(2100 5825);
DISPLAY 0.872340 (2100 5825);
PAINT AQUA (2100 5825);
DISPLAY INVISIBLE (2100 5825);
FORCEADD OFFPAGE..2
(3225 5275);
FORCEPROP 2 LAST $XR0 81 
J 0
(3414 5275);
DISPLAY 0.638298 (3414 5275);
PAINT MONO (3414 5275);
FORCEPROP 2 LAST CDS_LIB standard
J 0
(3225 5275);
DISPLAY INVISIBLE (3225 5275);
FORCEPROP 1 LAST OFFPAGE TRUE
J 0
(3550 5150);
DISPLAY 0.872340 (3550 5150);
PAINT AQUA (3550 5150);
DISPLAY INVISIBLE (3550 5150);
FORCEPROP 1 LAST COMMENT_BODY TRUE
J 0
(3180 5180);
DISPLAY 0.872340 (3180 5180);
PAINT GREEN (3180 5180);
DISPLAY INVISIBLE (3180 5180);
FORCEPROP 2 LAST PATH I124
J 0
(3425 5325);
DISPLAY 1.021277 (3425 5325);
DISPLAY INVISIBLE (3425 5325);
FORCEADD Q_CAP..1
(2950 4875);
FORCEPROP 1 LAST LOCATION C1804
J 0
(3000 4975);
DISPLAY 0.638298 (3000 4975);
FORCEPROP 2 LAST $SEC 1
J 0
(3000 5075);
DISPLAY 0.680851 (3000 5075);
PAINT MONO (3000 5075);
DISPLAY INVISIBLE (3000 5075);
FORCEPROP 2 LAST CDS_SEC 1
J 0
(3000 5075);
DISPLAY 1.021277 (3000 5075);
DISPLAY INVISIBLE (3000 5075);
FORCEPROP 1 LASTPIN (2950 4975) $PN 1
J 0
(2960 4955);
DISPLAY 0.787234 (2960 4955);
PAINT MONO (2960 4955);
FORCEPROP 1 LASTPIN (2950 4775) $PN 2
J 0
(2960 4755);
DISPLAY 0.787234 (2960 4755);
PAINT MONO (2960 4755);
FORCEPROP 1 LAST VALUE 0.1UF
J 0
(3000 4925);
DISPLAY 0.638298 (3000 4925);
FORCEPROP 1 LAST TOLERANCE 10%
J 0
(3000 4825);
DISPLAY 0.638298 (3000 4825);
FORCEPROP 1 LAST MATERIAL X7R
J 0
(3000 4775);
DISPLAY 0.638298 (3000 4775);
PAINT RED (3000 4775);
FORCEPROP 1 LAST PACK_TYPE 0402
J 0
(3000 4675);
DISPLAY 0.638298 (3000 4675);
FORCEPROP 1 LAST VOLTAGE 25V
J 0
(3000 4875);
DISPLAY 0.638298 (3000 4875);
FORCEPROP 2 LAST CDS_LIB pure_quanta
J 0
(2950 4875);
DISPLAY INVISIBLE (2950 4875);
FORCEPROP 1 LAST PATH I125
J 0
(3000 5025);
DISPLAY 0.978723 (3000 5025);
PAINT WHITE (3000 5025);
DISPLAY INVISIBLE (3000 5025);
FORCEPROP 1 LAST PART_NUMBER CH4104K1B00
J 0
(3000 4725);
DISPLAY 0.638298 (3000 4725);
DISPLAY INVISIBLE (3000 4725);
FORCEADD UNIVERSAL_GND..1
(2950 4675);
FORCEPROP 3 LASTPIN (2950 4725) SIG_NAME GND\g
J 0
(2960 4735);
DISPLAY 0.659574 (2960 4735);
PAINT MONO (2960 4735);
DISPLAY INVISIBLE (2960 4735);
FORCEPROP 2 LAST CDS_LIB pure_quanta_power
J 0
(2950 4675);
DISPLAY INVISIBLE (2950 4675);
FORCEPROP 1 LAST HDL_POWER GND
J 1
(2975 4600);
DISPLAY 0.872340 (2975 4600);
PAINT GREEN (2975 4600);
DISPLAY INVISIBLE (2975 4600);
FORCEPROP 1 LAST PATH I126
J 0
(3025 4675);
DISPLAY 0.872340 (3025 4675);
PAINT AQUA (3025 4675);
DISPLAY INVISIBLE (3025 4675);
FORCEADD UNIVERSAL_POWER..1
(1125 5550);
FORCEPROP 3 LASTPIN (1125 5500) SIG_NAME P3V3_AUX\g
J 0
(1135 5510);
DISPLAY 0.659574 (1135 5510);
PAINT MONO (1135 5510);
DISPLAY INVISIBLE (1135 5510);
FORCEPROP 1 LAST HDL_POWER P3V3_AUX
J 1
(1125 5600);
DISPLAY 0.872340 (1125 5600);
PAINT GREEN (1125 5600);
FORCEPROP 2 LAST CDS_LIB pure_quanta_power
J 0
(1125 5550);
PAINT MONO (1125 5550);
DISPLAY INVISIBLE (1125 5550);
FORCEPROP 1 LAST PATH I128
J 0
(1175 5575);
DISPLAY 0.872340 (1175 5575);
PAINT AQUA (1175 5575);
DISPLAY INVISIBLE (1175 5575);
FORCEADD Q_RES..2
(1125 5250);
FORCEPROP 1 LAST LOCATION R3034
J 0
(1170 5375);
DISPLAY 0.638298 (1170 5375);
FORCEPROP 2 LAST $SEC 1
J 0
(1175 5475);
DISPLAY 0.680851 (1175 5475);
PAINT MONO (1175 5475);
DISPLAY INVISIBLE (1175 5475);
FORCEPROP 2 LAST CDS_SEC 1
J 0
(1175 5475);
DISPLAY 1.021277 (1175 5475);
DISPLAY INVISIBLE (1175 5475);
FORCEPROP 1 LASTPIN (1125 5350) $PN 1
J 0
(1130 5312);
DISPLAY 0.787234 (1130 5312);
FORCEPROP 1 LASTPIN (1125 5150) $PN 2
J 0
(1130 5160);
DISPLAY 0.787234 (1130 5160);
FORCEPROP 1 LAST VALUE 4.7K
J 0
(1170 5325);
DISPLAY 0.638298 (1170 5325);
FORCEPROP 1 LAST PACK_TYPE 0402LF
J 0
(1165 5125);
DISPLAY 0.638298 (1165 5125);
FORCEPROP 1 LAST MATERIAL CHIP
J 0
(1165 5175);
DISPLAY 0.638298 (1165 5175);
FORCEPROP 1 LAST WATTAGE 1/16W
J 0
(1165 5225);
DISPLAY 0.638298 (1165 5225);
FORCEPROP 1 LAST TOLERANCE 5%
J 0
(1170 5275);
DISPLAY 0.638298 (1170 5275);
FORCEPROP 2 LAST CDS_LIB pure_quanta
J 0
(1125 5250);
PAINT MONO (1125 5250);
DISPLAY INVISIBLE (1125 5250);
FORCEPROP 1 LAST PATH I129
J 0
(1175 5425);
DISPLAY 0.978723 (1175 5425);
PAINT WHITE (1175 5425);
DISPLAY INVISIBLE (1175 5425);
FORCEPROP 1 LAST PART_NUMBER CS24702JB10
J 0
(1165 5075);
DISPLAY 0.638298 (1165 5075);
DISPLAY INVISIBLE (1165 5075);
FORCEADD UNIVERSAL_POWER..1
(-3525 8225);
FORCEPROP 3 LASTPIN (-3525 8175) SIG_NAME P3V3_AUX\g
J 0
(-3515 8185);
DISPLAY 0.659574 (-3515 8185);
PAINT MONO (-3515 8185);
DISPLAY INVISIBLE (-3515 8185);
FORCEPROP 1 LAST HDL_POWER P3V3_AUX
J 1
(-3525 8275);
DISPLAY 0.872340 (-3525 8275);
PAINT GREEN (-3525 8275);
FORCEPROP 2 LAST CDS_LIB pure_quanta_power
J 0
(-3525 8225);
PAINT MONO (-3525 8225);
DISPLAY INVISIBLE (-3525 8225);
FORCEPROP 1 LAST PATH I13
J 0
(-3475 8250);
DISPLAY 0.872340 (-3475 8250);
PAINT AQUA (-3475 8250);
DISPLAY INVISIBLE (-3475 8250);
FORCEADD UNIVERSAL_GND..1
(2050 4675);
FORCEPROP 3 LASTPIN (2050 4725) SIG_NAME GND\g
J 0
(2060 4735);
DISPLAY 0.659574 (2060 4735);
PAINT MONO (2060 4735);
DISPLAY INVISIBLE (2060 4735);
FORCEPROP 2 LAST CDS_LIB pure_quanta_power
J 0
(2050 4675);
DISPLAY INVISIBLE (2050 4675);
FORCEPROP 1 LAST HDL_POWER GND
J 1
(2075 4600);
DISPLAY 0.872340 (2075 4600);
PAINT GREEN (2075 4600);
DISPLAY INVISIBLE (2075 4600);
FORCEPROP 1 LAST PATH I130
J 0
(2125 4675);
DISPLAY 0.872340 (2125 4675);
PAINT AQUA (2125 4675);
DISPLAY INVISIBLE (2125 4675);
FORCEADD UNIVERSAL_GND..1
(1125 4400);
FORCEPROP 3 LASTPIN (1125 4450) SIG_NAME GND\g
J 0
(1135 4460);
DISPLAY 0.659574 (1135 4460);
PAINT MONO (1135 4460);
DISPLAY INVISIBLE (1135 4460);
FORCEPROP 2 LAST CDS_LIB pure_quanta_power
J 0
(1125 4400);
DISPLAY INVISIBLE (1125 4400);
FORCEPROP 1 LAST HDL_POWER GND
J 1
(1150 4325);
DISPLAY 0.872340 (1150 4325);
PAINT GREEN (1150 4325);
DISPLAY INVISIBLE (1150 4325);
FORCEPROP 1 LAST PATH I131
J 0
(1200 4400);
DISPLAY 0.872340 (1200 4400);
PAINT AQUA (1200 4400);
DISPLAY INVISIBLE (1200 4400);
FORCEADD UNIVERSAL_POWER..1
(-125 5250);
FORCEPROP 3 LASTPIN (-125 5200) SIG_NAME P3V3_AUX\g
J 0
(-115 5210);
DISPLAY 0.659574 (-115 5210);
PAINT MONO (-115 5210);
DISPLAY INVISIBLE (-115 5210);
FORCEPROP 1 LAST HDL_POWER P3V3_AUX
J 1
(-125 5300);
DISPLAY 0.872340 (-125 5300);
PAINT GREEN (-125 5300);
FORCEPROP 2 LAST CDS_LIB pure_quanta_power
J 0
(-125 5250);
PAINT MONO (-125 5250);
DISPLAY INVISIBLE (-125 5250);
FORCEPROP 1 LAST PATH I132
J 0
(-75 5275);
DISPLAY 0.872340 (-75 5275);
PAINT AQUA (-75 5275);
DISPLAY INVISIBLE (-75 5275);
FORCEADD Q_RES..2
(-100 4525);
FORCEPROP 1 LAST LOCATION R3032
J 0
(-55 4650);
DISPLAY 0.978723 (-55 4650);
FORCEPROP 0 LAST $SEC 1
J 0
(-50 4700);
DISPLAY 0.680851 (-50 4700);
PAINT MONO (-50 4700);
DISPLAY INVISIBLE (-50 4700);
FORCEPROP 0 LAST CDS_SEC 1
J 0
(-50 4700);
DISPLAY 1.021277 (-50 4700);
DISPLAY INVISIBLE (-50 4700);
FORCEPROP 1 LASTPIN (-100 4625) $PN 1
J 0
(-95 4587);
DISPLAY 0.787234 (-95 4587);
PAINT MONO (-95 4587);
FORCEPROP 1 LASTPIN (-100 4425) $PN 2
J 0
(-95 4435);
DISPLAY 0.787234 (-95 4435);
PAINT MONO (-95 4435);
FORCEPROP 1 LAST VALUE 100K
J 0
(-55 4600);
DISPLAY 0.510638 (-55 4600);
FORCEPROP 1 LAST TOLERANCE 1%
J 0
(-55 4550);
DISPLAY 0.510638 (-55 4550);
FORCEPROP 1 LAST WATTAGE 1/16W
J 0
(-60 4500);
DISPLAY 0.510638 (-60 4500);
FORCEPROP 1 LAST MATERIAL EMPTY
J 0
(-60 4450);
DISPLAY 0.510638 (-60 4450);
FORCEPROP 1 LAST PACK_TYPE 0402LF
J 0
(-60 4350);
DISPLAY 0.510638 (-60 4350);
FORCEPROP 2 LAST CDS_LIB pure_quanta
J 0
(-100 4525);
DISPLAY INVISIBLE (-100 4525);
FORCEPROP 1 LAST PATH I134
J 0
(-50 4700);
DISPLAY 0.978723 (-50 4700);
PAINT WHITE (-50 4700);
DISPLAY INVISIBLE (-50 4700);
FORCEPROP 1 LAST PART_NUMBER CS41002FB09
J 0
(-60 4400);
DISPLAY 0.510638 (-60 4400);
DISPLAY INVISIBLE (-60 4400);
FORCEADD UNIVERSAL_GND..1
(-100 4325);
FORCEPROP 3 LASTPIN (-100 4375) SIG_NAME GND\g
J 0
(-90 4385);
DISPLAY 0.659574 (-90 4385);
PAINT MONO (-90 4385);
DISPLAY INVISIBLE (-90 4385);
FORCEPROP 2 LAST CDS_LIB pure_quanta_power
J 0
(-100 4325);
DISPLAY INVISIBLE (-100 4325);
FORCEPROP 1 LAST HDL_POWER GND
J 1
(-75 4250);
DISPLAY 0.872340 (-75 4250);
PAINT GREEN (-75 4250);
DISPLAY INVISIBLE (-75 4250);
FORCEPROP 1 LAST PATH I135
J 0
(-25 4325);
DISPLAY 0.872340 (-25 4325);
PAINT AQUA (-25 4325);
DISPLAY INVISIBLE (-25 4325);
FORCEADD OFFPAGE..4
R 2
(-400 4725);
FORCEPROP 2 LAST $XR0 120 
J 0
(-652 4725);
DISPLAY 0.638298 (-652 4725);
PAINT MONO (-652 4725);
FORCEPROP 2 LAST CDS_LIB standard
J 0
(-400 4725);
DISPLAY INVISIBLE (-400 4725);
FORCEPROP 1 LAST OFFPAGE TRUE
J 2
(-725 4600);
DISPLAY 0.872340 (-725 4600);
PAINT GREEN (-725 4600);
DISPLAY INVISIBLE (-725 4600);
FORCEPROP 1 LAST COMMENT_BODY TRUE
J 2
(-375 4625);
DISPLAY 0.872340 (-375 4625);
PAINT GREEN (-375 4625);
DISPLAY INVISIBLE (-375 4625);
FORCEPROP 2 LAST PATH I136
J 0
(-650 4775);
DISPLAY 1.021277 (-650 4775);
DISPLAY INVISIBLE (-650 4775);
FORCEADD OFFPAGE..4
R 2
(-4950 3025);
FORCEPROP 2 LAST $XR0 120 
J 0
(-5232 3025);
DISPLAY 0.638298 (-5232 3025);
PAINT MONO (-5232 3025);
FORCEPROP 2 LAST CDS_LIB standard
J 0
(-4950 3025);
DISPLAY INVISIBLE (-4950 3025);
FORCEPROP 1 LAST OFFPAGE TRUE
J 2
(-5275 2900);
DISPLAY 0.872340 (-5275 2900);
PAINT GREEN (-5275 2900);
DISPLAY INVISIBLE (-5275 2900);
FORCEPROP 1 LAST COMMENT_BODY TRUE
J 2
(-4925 2925);
DISPLAY 0.872340 (-4925 2925);
PAINT GREEN (-4925 2925);
DISPLAY INVISIBLE (-4925 2925);
FORCEPROP 2 LAST PATH I137
J 0
(-5200 3075);
DISPLAY 1.021277 (-5200 3075);
DISPLAY INVISIBLE (-5200 3075);
FORCEADD UNIVERSAL_GND..1
(-4650 2625);
FORCEPROP 3 LASTPIN (-4650 2675) SIG_NAME GND\g
J 0
(-4640 2685);
DISPLAY 0.659574 (-4640 2685);
PAINT MONO (-4640 2685);
DISPLAY INVISIBLE (-4640 2685);
FORCEPROP 2 LAST CDS_LIB pure_quanta_power
J 0
(-4650 2625);
DISPLAY INVISIBLE (-4650 2625);
FORCEPROP 1 LAST HDL_POWER GND
J 1
(-4625 2550);
DISPLAY 0.872340 (-4625 2550);
PAINT GREEN (-4625 2550);
DISPLAY INVISIBLE (-4625 2550);
FORCEPROP 1 LAST PATH I138
J 0
(-4575 2625);
DISPLAY 0.872340 (-4575 2625);
PAINT AQUA (-4575 2625);
DISPLAY INVISIBLE (-4575 2625);
FORCEADD Q_RES..2
(-4650 2825);
FORCEPROP 1 LAST LOCATION R3028
J 0
(-4605 2950);
DISPLAY 0.978723 (-4605 2950);
FORCEPROP 0 LAST $SEC 1
J 0
(-4600 3000);
DISPLAY 0.680851 (-4600 3000);
PAINT MONO (-4600 3000);
DISPLAY INVISIBLE (-4600 3000);
FORCEPROP 0 LAST CDS_SEC 1
J 0
(-4600 3000);
DISPLAY 1.021277 (-4600 3000);
DISPLAY INVISIBLE (-4600 3000);
FORCEPROP 1 LASTPIN (-4650 2925) $PN 1
J 0
(-4645 2887);
DISPLAY 0.787234 (-4645 2887);
PAINT MONO (-4645 2887);
FORCEPROP 1 LASTPIN (-4650 2725) $PN 2
J 0
(-4645 2735);
DISPLAY 0.787234 (-4645 2735);
PAINT MONO (-4645 2735);
FORCEPROP 1 LAST PACK_TYPE 0402LF
J 0
(-4610 2650);
DISPLAY 0.510638 (-4610 2650);
FORCEPROP 1 LAST TOLERANCE 1%
J 0
(-4605 2850);
DISPLAY 0.510638 (-4605 2850);
FORCEPROP 1 LAST MATERIAL EMPTY
J 0
(-4610 2750);
DISPLAY 0.510638 (-4610 2750);
FORCEPROP 1 LAST VALUE 100K
J 0
(-4605 2900);
DISPLAY 0.510638 (-4605 2900);
FORCEPROP 1 LAST WATTAGE 1/16W
J 0
(-4610 2800);
DISPLAY 0.510638 (-4610 2800);
FORCEPROP 2 LAST CDS_LIB pure_quanta
J 0
(-4650 2825);
DISPLAY INVISIBLE (-4650 2825);
FORCEPROP 1 LAST PATH I139
J 0
(-4600 3000);
DISPLAY 0.978723 (-4600 3000);
PAINT WHITE (-4600 3000);
DISPLAY INVISIBLE (-4600 3000);
FORCEPROP 1 LAST PART_NUMBER CS41002FB09
J 0
(-4610 2700);
DISPLAY 0.510638 (-4610 2700);
DISPLAY INVISIBLE (-4610 2700);
FORCEADD Q_RES..2
(-3525 8000);
FORCEPROP 1 LAST LOCATION R2835
J 0
(-3480 8125);
DISPLAY 0.638298 (-3480 8125);
FORCEPROP 2 LAST $SEC 1
J 0
(-3475 8225);
DISPLAY 0.680851 (-3475 8225);
PAINT MONO (-3475 8225);
DISPLAY INVISIBLE (-3475 8225);
FORCEPROP 2 LAST CDS_SEC 1
J 0
(-3475 8225);
DISPLAY 1.021277 (-3475 8225);
DISPLAY INVISIBLE (-3475 8225);
FORCEPROP 1 LASTPIN (-3525 8100) $PN 1
J 0
(-3520 8062);
DISPLAY 0.787234 (-3520 8062);
FORCEPROP 1 LASTPIN (-3525 7900) $PN 2
J 0
(-3520 7910);
DISPLAY 0.787234 (-3520 7910);
FORCEPROP 1 LAST PACK_TYPE 0402LF
J 0
(-3485 7875);
DISPLAY 0.638298 (-3485 7875);
FORCEPROP 1 LAST VALUE 4.7K
J 0
(-3480 8075);
DISPLAY 0.638298 (-3480 8075);
FORCEPROP 1 LAST TOLERANCE 5%
J 0
(-3480 8025);
DISPLAY 0.638298 (-3480 8025);
FORCEPROP 1 LAST MATERIAL CHIP
J 0
(-3485 7925);
DISPLAY 0.638298 (-3485 7925);
FORCEPROP 1 LAST WATTAGE 1/16W
J 0
(-3485 7975);
DISPLAY 0.638298 (-3485 7975);
FORCEPROP 2 LAST CDS_LIB pure_quanta
J 0
(-3525 8000);
PAINT MONO (-3525 8000);
DISPLAY INVISIBLE (-3525 8000);
FORCEPROP 1 LAST PATH I14
J 0
(-3475 8175);
DISPLAY 0.978723 (-3475 8175);
PAINT WHITE (-3475 8175);
DISPLAY INVISIBLE (-3475 8175);
FORCEPROP 1 LAST PART_NUMBER CS24702JB10
J 0
(-3485 7825);
DISPLAY 0.638298 (-3485 7825);
DISPLAY INVISIBLE (-3485 7825);
FORCEADD UNIVERSAL_POWER..1
(-4675 3550);
FORCEPROP 3 LASTPIN (-4675 3500) SIG_NAME P3V3_AUX\g
J 0
(-4665 3510);
DISPLAY 0.659574 (-4665 3510);
PAINT MONO (-4665 3510);
DISPLAY INVISIBLE (-4665 3510);
FORCEPROP 1 LAST HDL_POWER P3V3_AUX
J 1
(-4675 3600);
DISPLAY 0.872340 (-4675 3600);
PAINT GREEN (-4675 3600);
FORCEPROP 2 LAST CDS_LIB pure_quanta_power
J 0
(-4675 3550);
PAINT MONO (-4675 3550);
DISPLAY INVISIBLE (-4675 3550);
FORCEPROP 1 LAST PATH I141
J 0
(-4625 3575);
DISPLAY 0.872340 (-4625 3575);
PAINT AQUA (-4625 3575);
DISPLAY INVISIBLE (-4625 3575);
FORCEADD UNIVERSAL_GND..1
(-3425 2700);
FORCEPROP 3 LASTPIN (-3425 2750) SIG_NAME GND\g
J 0
(-3415 2760);
DISPLAY 0.659574 (-3415 2760);
PAINT MONO (-3415 2760);
DISPLAY INVISIBLE (-3415 2760);
FORCEPROP 2 LAST CDS_LIB pure_quanta_power
J 0
(-3425 2700);
DISPLAY INVISIBLE (-3425 2700);
FORCEPROP 1 LAST HDL_POWER GND
J 1
(-3400 2625);
DISPLAY 0.872340 (-3400 2625);
PAINT GREEN (-3400 2625);
DISPLAY INVISIBLE (-3400 2625);
FORCEPROP 1 LAST PATH I142
J 0
(-3350 2700);
DISPLAY 0.872340 (-3350 2700);
PAINT AQUA (-3350 2700);
DISPLAY INVISIBLE (-3350 2700);
FORCEADD UNIVERSAL_GND..1
(-2500 2975);
FORCEPROP 3 LASTPIN (-2500 3025) SIG_NAME GND\g
J 0
(-2490 3035);
DISPLAY 0.659574 (-2490 3035);
PAINT MONO (-2490 3035);
DISPLAY INVISIBLE (-2490 3035);
FORCEPROP 2 LAST CDS_LIB pure_quanta_power
J 0
(-2500 2975);
DISPLAY INVISIBLE (-2500 2975);
FORCEPROP 1 LAST HDL_POWER GND
J 1
(-2475 2900);
DISPLAY 0.872340 (-2475 2900);
PAINT GREEN (-2475 2900);
DISPLAY INVISIBLE (-2475 2900);
FORCEPROP 1 LAST PATH I143
J 0
(-2425 2975);
DISPLAY 0.872340 (-2425 2975);
PAINT AQUA (-2425 2975);
DISPLAY INVISIBLE (-2425 2975);
FORCEADD Q_RES..2
(-3425 3550);
FORCEPROP 1 LAST LOCATION R3029
J 0
(-3380 3675);
DISPLAY 0.638298 (-3380 3675);
FORCEPROP 2 LAST $SEC 1
J 0
(-3375 3775);
DISPLAY 0.680851 (-3375 3775);
PAINT MONO (-3375 3775);
DISPLAY INVISIBLE (-3375 3775);
FORCEPROP 2 LAST CDS_SEC 1
J 0
(-3375 3775);
DISPLAY 1.021277 (-3375 3775);
DISPLAY INVISIBLE (-3375 3775);
FORCEPROP 1 LASTPIN (-3425 3650) $PN 1
J 0
(-3420 3612);
DISPLAY 0.787234 (-3420 3612);
FORCEPROP 1 LASTPIN (-3425 3450) $PN 2
J 0
(-3420 3460);
DISPLAY 0.787234 (-3420 3460);
FORCEPROP 1 LAST TOLERANCE 5%
J 0
(-3380 3575);
DISPLAY 0.638298 (-3380 3575);
FORCEPROP 1 LAST MATERIAL CHIP
J 0
(-3385 3475);
DISPLAY 0.638298 (-3385 3475);
FORCEPROP 1 LAST WATTAGE 1/16W
J 0
(-3385 3525);
DISPLAY 0.638298 (-3385 3525);
FORCEPROP 1 LAST PACK_TYPE 0402LF
J 0
(-3385 3425);
DISPLAY 0.638298 (-3385 3425);
FORCEPROP 1 LAST VALUE 4.7K
J 0
(-3380 3625);
DISPLAY 0.638298 (-3380 3625);
FORCEPROP 2 LAST CDS_LIB pure_quanta
J 0
(-3425 3550);
PAINT MONO (-3425 3550);
DISPLAY INVISIBLE (-3425 3550);
FORCEPROP 1 LAST PATH I144
J 0
(-3375 3725);
DISPLAY 0.978723 (-3375 3725);
PAINT WHITE (-3375 3725);
DISPLAY INVISIBLE (-3375 3725);
FORCEPROP 1 LAST PART_NUMBER CS24702JB10
J 0
(-3385 3375);
DISPLAY 0.638298 (-3385 3375);
DISPLAY INVISIBLE (-3385 3375);
FORCEADD UNIVERSAL_POWER..1
(-3425 3850);
FORCEPROP 3 LASTPIN (-3425 3800) SIG_NAME P3V3_AUX\g
J 0
(-3415 3810);
DISPLAY 0.659574 (-3415 3810);
PAINT MONO (-3415 3810);
DISPLAY INVISIBLE (-3415 3810);
FORCEPROP 1 LAST HDL_POWER P3V3_AUX
J 1
(-3425 3900);
DISPLAY 0.872340 (-3425 3900);
PAINT GREEN (-3425 3900);
FORCEPROP 2 LAST CDS_LIB pure_quanta_power
J 0
(-3425 3850);
PAINT MONO (-3425 3850);
DISPLAY INVISIBLE (-3425 3850);
FORCEPROP 1 LAST PATH I145
J 0
(-3375 3875);
DISPLAY 0.872340 (-3375 3875);
PAINT AQUA (-3375 3875);
DISPLAY INVISIBLE (-3375 3875);
FORCEADD UNIVERSAL_GND..1
(-1600 2975);
FORCEPROP 3 LASTPIN (-1600 3025) SIG_NAME GND\g
J 0
(-1590 3035);
DISPLAY 0.659574 (-1590 3035);
PAINT MONO (-1590 3035);
DISPLAY INVISIBLE (-1590 3035);
FORCEPROP 2 LAST CDS_LIB pure_quanta_power
J 0
(-1600 2975);
DISPLAY INVISIBLE (-1600 2975);
FORCEPROP 1 LAST HDL_POWER GND
J 1
(-1575 2900);
DISPLAY 0.872340 (-1575 2900);
PAINT GREEN (-1575 2900);
DISPLAY INVISIBLE (-1575 2900);
FORCEPROP 1 LAST PATH I147
J 0
(-1525 2975);
DISPLAY 0.872340 (-1525 2975);
PAINT AQUA (-1525 2975);
DISPLAY INVISIBLE (-1525 2975);
FORCEADD Q_CAP..1
(-1600 3175);
FORCEPROP 1 LAST LOCATION C1802
J 0
(-1550 3275);
DISPLAY 0.638298 (-1550 3275);
FORCEPROP 2 LAST $SEC 1
J 0
(-1550 3375);
DISPLAY 0.680851 (-1550 3375);
PAINT MONO (-1550 3375);
DISPLAY INVISIBLE (-1550 3375);
FORCEPROP 2 LAST CDS_SEC 1
J 0
(-1550 3375);
DISPLAY 1.021277 (-1550 3375);
DISPLAY INVISIBLE (-1550 3375);
FORCEPROP 1 LASTPIN (-1600 3275) $PN 1
J 0
(-1590 3255);
DISPLAY 0.787234 (-1590 3255);
PAINT MONO (-1590 3255);
FORCEPROP 1 LASTPIN (-1600 3075) $PN 2
J 0
(-1590 3055);
DISPLAY 0.787234 (-1590 3055);
PAINT MONO (-1590 3055);
FORCEPROP 1 LAST VOLTAGE 25V
J 0
(-1550 3175);
DISPLAY 0.638298 (-1550 3175);
FORCEPROP 1 LAST VALUE 0.1UF
J 0
(-1550 3225);
DISPLAY 0.638298 (-1550 3225);
FORCEPROP 1 LAST MATERIAL X7R
J 0
(-1550 3075);
DISPLAY 0.638298 (-1550 3075);
PAINT RED (-1550 3075);
FORCEPROP 1 LAST PACK_TYPE 0402
J 0
(-1550 2975);
DISPLAY 0.638298 (-1550 2975);
FORCEPROP 1 LAST TOLERANCE 10%
J 0
(-1550 3125);
DISPLAY 0.638298 (-1550 3125);
FORCEPROP 2 LAST CDS_LIB pure_quanta
J 0
(-1600 3175);
DISPLAY INVISIBLE (-1600 3175);
FORCEPROP 1 LAST PATH I148
J 0
(-1550 3325);
DISPLAY 0.978723 (-1550 3325);
PAINT WHITE (-1550 3325);
DISPLAY INVISIBLE (-1550 3325);
FORCEPROP 1 LAST PART_NUMBER CH4104K1B00
J 0
(-1550 3025);
DISPLAY 0.638298 (-1550 3025);
DISPLAY INVISIBLE (-1550 3025);
FORCEADD OFFPAGE..2
(-1325 3575);
FORCEPROP 2 LAST $XR0 81 
J 0
(-1136 3575);
DISPLAY 0.638298 (-1136 3575);
PAINT MONO (-1136 3575);
FORCEPROP 2 LAST CDS_LIB standard
J 0
(-1325 3575);
DISPLAY INVISIBLE (-1325 3575);
FORCEPROP 1 LAST OFFPAGE TRUE
J 0
(-1000 3450);
DISPLAY 0.872340 (-1000 3450);
PAINT AQUA (-1000 3450);
DISPLAY INVISIBLE (-1000 3450);
FORCEPROP 1 LAST COMMENT_BODY TRUE
J 0
(-1370 3480);
DISPLAY 0.872340 (-1370 3480);
PAINT GREEN (-1370 3480);
DISPLAY INVISIBLE (-1370 3480);
FORCEPROP 2 LAST PATH I149
J 0
(-1125 3625);
DISPLAY 1.021277 (-1125 3625);
DISPLAY INVISIBLE (-1125 3625);
FORCEADD UNIVERSAL_POWER..1
(-2500 4100);
FORCEPROP 3 LASTPIN (-2500 4050) SIG_NAME P3V3_AUX\g
J 0
(-2490 4060);
DISPLAY 0.659574 (-2490 4060);
PAINT MONO (-2490 4060);
DISPLAY INVISIBLE (-2490 4060);
FORCEPROP 1 LAST HDL_POWER P3V3_AUX
J 1
(-2500 4150);
DISPLAY 0.872340 (-2500 4150);
PAINT GREEN (-2500 4150);
FORCEPROP 2 LAST CDS_LIB pure_quanta_power
J 0
(-2500 4100);
DISPLAY INVISIBLE (-2500 4100);
FORCEPROP 1 LAST PATH I150
J 0
(-2450 4125);
DISPLAY 0.872340 (-2450 4125);
PAINT AQUA (-2450 4125);
DISPLAY INVISIBLE (-2450 4125);
FORCEADD MOSFET_NCH_DUAL..2
(-2550 3350);
FORCEPROP 1 LAST LOCATION Q75
J 0
(-2399 3326);
DISPLAY 0.723404 (-2399 3326);
PAINT GREEN (-2399 3326);
FORCEPROP 0 LAST $SEC 2
J 0
(-2375 3475);
DISPLAY 0.680851 (-2375 3475);
PAINT MONO (-2375 3475);
DISPLAY INVISIBLE (-2375 3475);
FORCEPROP 0 LAST CDS_SEC 2
J 0
(-2375 3475);
DISPLAY 1.021277 (-2375 3475);
DISPLAY INVISIBLE (-2375 3475);
FORCEPROP 0 LASTPIN (-2500 3550) $PN 3
R 1
J 0
(-2510 3560);
DISPLAY 0.680851 (-2510 3560);
PAINT MONO (-2510 3560);
FORCEPROP 0 LASTPIN (-2750 3300) $PN 5
J 2
(-2760 3310);
DISPLAY 0.680851 (-2760 3310);
PAINT MONO (-2760 3310);
FORCEPROP 0 LASTPIN (-2500 3150) $PN 4
R 1
J 2
(-2510 3140);
DISPLAY 0.680851 (-2510 3140);
PAINT MONO (-2510 3140);
FORCEPROP 2 LAST PART_TYPE SMLF
J 0
(-2375 3425);
DISPLAY 1.021277 (-2375 3425);
FORCEPROP 2 LAST VALUE PJT138K
J 0
(-2375 3375);
DISPLAY 1.021277 (-2375 3375);
FORCEPROP 1 LAST MATERIAL IC
J 0
(-2399 3201);
DISPLAY 0.723404 (-2399 3201);
PAINT GREEN (-2399 3201);
FORCEPROP 2 LAST CDS_LIB pure_quanta
J 0
(-2550 3350);
DISPLAY INVISIBLE (-2550 3350);
FORCEPROP 1 LAST NEEDS_NO_SIZE TRUE
J 0
(-2400 3241);
DISPLAY 0.468085 (-2400 3241);
PAINT GREEN (-2400 3241);
DISPLAY INVISIBLE (-2400 3241);
FORCEPROP 1 LAST CDS_LMAN_SYM_OUTLINE -150,150,150,-150
J 0
(-2550 3350);
DISPLAY 0.468085 (-2550 3350);
PAINT GREEN (-2550 3350);
DISPLAY INVISIBLE (-2550 3350);
FORCEPROP 1 LAST PATH I151
J 0
(-2400 3200);
DISPLAY 0.723404 (-2400 3200);
PAINT GREEN (-2400 3200);
DISPLAY INVISIBLE (-2400 3200);
FORCEPROP 1 LAST PART_NUMBER BAM138K0003
J 0
(-2399 3256);
DISPLAY 0.723404 (-2399 3256);
PAINT GREEN (-2399 3256);
DISPLAY INVISIBLE (-2399 3256);
FORCEADD MOSFET_NCH_DUAL..1
(-3475 3075);
FORCEPROP 1 LAST LOCATION Q75
J 0
(-3324 3049);
DISPLAY 0.723404 (-3324 3049);
PAINT GREEN (-3324 3049);
FORCEPROP 0 LAST $SEC 1
J 0
(-3300 3200);
DISPLAY 0.680851 (-3300 3200);
PAINT MONO (-3300 3200);
DISPLAY INVISIBLE (-3300 3200);
FORCEPROP 2 LAST CDS_SEC 1
J 0
(-3300 3200);
DISPLAY 1.021277 (-3300 3200);
DISPLAY INVISIBLE (-3300 3200);
FORCEPROP 0 LASTPIN (-3425 3275) $PN 6
R 1
J 0
(-3435 3285);
DISPLAY 0.680851 (-3435 3285);
PAINT MONO (-3435 3285);
FORCEPROP 0 LASTPIN (-3675 3025) $PN 2
J 2
(-3685 3035);
DISPLAY 0.680851 (-3685 3035);
PAINT MONO (-3685 3035);
FORCEPROP 0 LASTPIN (-3425 2875) $PN 1
R 1
J 2
(-3435 2865);
DISPLAY 0.680851 (-3435 2865);
PAINT MONO (-3435 2865);
FORCEPROP 2 LAST PART_TYPE SMLF
J 0
(-3300 3150);
DISPLAY 1.021277 (-3300 3150);
FORCEPROP 2 LAST VALUE PJT138K
J 0
(-3300 3100);
DISPLAY 1.021277 (-3300 3100);
FORCEPROP 1 LAST MATERIAL IC
J 0
(-3324 2924);
DISPLAY 0.723404 (-3324 2924);
PAINT GREEN (-3324 2924);
FORCEPROP 2 LAST CDS_LIB pure_quanta
J 0
(-3475 3075);
DISPLAY INVISIBLE (-3475 3075);
FORCEPROP 1 LAST NEEDS_NO_SIZE TRUE
J 0
(-3475 3074);
DISPLAY 0.468085 (-3475 3074);
PAINT GREEN (-3475 3074);
DISPLAY INVISIBLE (-3475 3074);
FORCEPROP 1 LAST CDS_LMAN_SYM_OUTLINE -150,150,150,-150
J 0
(-3475 3075);
DISPLAY 0.468085 (-3475 3075);
PAINT GREEN (-3475 3075);
DISPLAY INVISIBLE (-3475 3075);
FORCEPROP 1 LAST PATH I152
J 0
(-3475 3075);
DISPLAY 0.723404 (-3475 3075);
PAINT GREEN (-3475 3075);
DISPLAY INVISIBLE (-3475 3075);
FORCEPROP 1 LAST PART_NUMBER BAM138K0003
J 0
(-3324 2989);
DISPLAY 0.723404 (-3324 2989);
PAINT GREEN (-3324 2989);
DISPLAY INVISIBLE (-3324 2989);
FORCEADD UNIVERSAL_POWER..1
(2000 4250);
FORCEPROP 3 LASTPIN (2000 4200) SIG_NAME P3V3_AUX\g
J 0
(2010 4210);
DISPLAY 0.659574 (2010 4210);
PAINT MONO (2010 4210);
DISPLAY INVISIBLE (2010 4210);
FORCEPROP 1 LAST HDL_POWER P3V3_AUX
J 1
(2000 4300);
DISPLAY 0.872340 (2000 4300);
PAINT GREEN (2000 4300);
FORCEPROP 2 LAST CDS_LIB pure_quanta_power
J 0
(2000 4250);
DISPLAY INVISIBLE (2000 4250);
FORCEPROP 1 LAST PATH I153
J 0
(2050 4275);
DISPLAY 0.872340 (2050 4275);
PAINT AQUA (2050 4275);
DISPLAY INVISIBLE (2050 4275);
FORCEADD MOSFET_NCH_DUAL..1
(1025 3225);
FORCEPROP 1 LAST LOCATION Q96
J 0
(1176 3199);
DISPLAY 0.723404 (1176 3199);
PAINT GREEN (1176 3199);
FORCEPROP 0 LAST $SEC 1
J 0
(1200 3350);
DISPLAY 0.680851 (1200 3350);
PAINT MONO (1200 3350);
DISPLAY INVISIBLE (1200 3350);
FORCEPROP 2 LAST CDS_SEC 1
J 0
(1200 3350);
DISPLAY 1.021277 (1200 3350);
DISPLAY INVISIBLE (1200 3350);
FORCEPROP 0 LASTPIN (1075 3425) $PN 6
R 1
J 0
(1065 3435);
DISPLAY 0.680851 (1065 3435);
PAINT MONO (1065 3435);
FORCEPROP 0 LASTPIN (825 3175) $PN 2
J 2
(815 3185);
DISPLAY 0.680851 (815 3185);
PAINT MONO (815 3185);
FORCEPROP 0 LASTPIN (1075 3025) $PN 1
R 1
J 2
(1065 3015);
DISPLAY 0.680851 (1065 3015);
PAINT MONO (1065 3015);
FORCEPROP 2 LAST PART_TYPE SMLF
J 0
(1200 3300);
DISPLAY 1.021277 (1200 3300);
FORCEPROP 1 LAST MATERIAL IC
J 0
(1176 3074);
DISPLAY 0.723404 (1176 3074);
PAINT GREEN (1176 3074);
FORCEPROP 2 LAST VALUE PJT138K
J 0
(1200 3250);
DISPLAY 1.021277 (1200 3250);
FORCEPROP 2 LAST CDS_LIB pure_quanta
J 0
(1025 3225);
DISPLAY INVISIBLE (1025 3225);
FORCEPROP 1 LAST NEEDS_NO_SIZE TRUE
J 0
(1025 3224);
DISPLAY 0.468085 (1025 3224);
PAINT GREEN (1025 3224);
DISPLAY INVISIBLE (1025 3224);
FORCEPROP 1 LAST CDS_LMAN_SYM_OUTLINE -150,150,150,-150
J 0
(1025 3225);
DISPLAY 0.468085 (1025 3225);
PAINT GREEN (1025 3225);
DISPLAY INVISIBLE (1025 3225);
FORCEPROP 1 LAST PATH I154
J 0
(1025 3225);
DISPLAY 0.723404 (1025 3225);
PAINT GREEN (1025 3225);
DISPLAY INVISIBLE (1025 3225);
FORCEPROP 1 LAST PART_NUMBER BAM138K0003
J 0
(1176 3139);
DISPLAY 0.723404 (1176 3139);
PAINT GREEN (1176 3139);
DISPLAY INVISIBLE (1176 3139);
FORCEADD OFFPAGE..2
(3175 3725);
FORCEPROP 2 LAST $XR0 81 
J 0
(3364 3725);
DISPLAY 0.638298 (3364 3725);
PAINT MONO (3364 3725);
FORCEPROP 2 LAST CDS_LIB standard
J 0
(3175 3725);
DISPLAY INVISIBLE (3175 3725);
FORCEPROP 1 LAST OFFPAGE TRUE
J 0
(3500 3600);
DISPLAY 0.872340 (3500 3600);
PAINT AQUA (3500 3600);
DISPLAY INVISIBLE (3500 3600);
FORCEPROP 1 LAST COMMENT_BODY TRUE
J 0
(3130 3630);
DISPLAY 0.872340 (3130 3630);
PAINT GREEN (3130 3630);
DISPLAY INVISIBLE (3130 3630);
FORCEPROP 2 LAST PATH I155
J 0
(3375 3775);
DISPLAY 1.021277 (3375 3775);
DISPLAY INVISIBLE (3375 3775);
FORCEADD Q_CAP..1
(2900 3325);
FORCEPROP 1 LAST LOCATION C1881
J 0
(2950 3425);
DISPLAY 0.638298 (2950 3425);
FORCEPROP 2 LAST $SEC 1
J 0
(2950 3525);
DISPLAY 0.680851 (2950 3525);
PAINT MONO (2950 3525);
DISPLAY INVISIBLE (2950 3525);
FORCEPROP 2 LAST CDS_SEC 1
J 0
(2950 3525);
DISPLAY 1.021277 (2950 3525);
DISPLAY INVISIBLE (2950 3525);
FORCEPROP 1 LASTPIN (2900 3425) $PN 1
J 0
(2910 3405);
DISPLAY 0.787234 (2910 3405);
PAINT MONO (2910 3405);
FORCEPROP 1 LASTPIN (2900 3225) $PN 2
J 0
(2910 3205);
DISPLAY 0.787234 (2910 3205);
PAINT MONO (2910 3205);
FORCEPROP 1 LAST VALUE 0.1UF
J 0
(2950 3375);
DISPLAY 0.638298 (2950 3375);
FORCEPROP 1 LAST PACK_TYPE 0402
J 0
(2950 3125);
DISPLAY 0.638298 (2950 3125);
FORCEPROP 1 LAST VOLTAGE 25V
J 0
(2950 3325);
DISPLAY 0.638298 (2950 3325);
FORCEPROP 1 LAST MATERIAL X7R
J 0
(2950 3225);
DISPLAY 0.638298 (2950 3225);
PAINT RED (2950 3225);
FORCEPROP 1 LAST TOLERANCE 10%
J 0
(2950 3275);
DISPLAY 0.638298 (2950 3275);
FORCEPROP 2 LAST CDS_LIB pure_quanta
J 0
(2900 3325);
DISPLAY INVISIBLE (2900 3325);
FORCEPROP 1 LAST PATH I156
J 0
(2950 3475);
DISPLAY 0.978723 (2950 3475);
PAINT WHITE (2950 3475);
DISPLAY INVISIBLE (2950 3475);
FORCEPROP 1 LAST PART_NUMBER CH4104K1B00
J 0
(2950 3175);
DISPLAY 0.638298 (2950 3175);
DISPLAY INVISIBLE (2950 3175);
FORCEADD UNIVERSAL_GND..1
(2900 3125);
FORCEPROP 3 LASTPIN (2900 3175) SIG_NAME GND\g
J 0
(2910 3185);
DISPLAY 0.659574 (2910 3185);
PAINT MONO (2910 3185);
DISPLAY INVISIBLE (2910 3185);
FORCEPROP 2 LAST CDS_LIB pure_quanta_power
J 0
(2900 3125);
DISPLAY INVISIBLE (2900 3125);
FORCEPROP 1 LAST HDL_POWER GND
J 1
(2925 3050);
DISPLAY 0.872340 (2925 3050);
PAINT GREEN (2925 3050);
DISPLAY INVISIBLE (2925 3050);
FORCEPROP 1 LAST PATH I157
J 0
(2975 3125);
DISPLAY 0.872340 (2975 3125);
PAINT AQUA (2975 3125);
DISPLAY INVISIBLE (2975 3125);
FORCEADD Q_RES..2
(2000 3950);
FORCEPROP 1 LAST LOCATION R3321
J 0
(2045 4075);
DISPLAY 0.978723 (2045 4075);
FORCEPROP 0 LAST $SEC 1
J 0
(2050 4125);
DISPLAY 0.680851 (2050 4125);
PAINT MONO (2050 4125);
DISPLAY INVISIBLE (2050 4125);
FORCEPROP 0 LAST CDS_SEC 1
J 0
(2050 4125);
DISPLAY 1.021277 (2050 4125);
DISPLAY INVISIBLE (2050 4125);
FORCEPROP 1 LASTPIN (2000 4050) $PN 1
J 0
(2005 4012);
DISPLAY 0.787234 (2005 4012);
PAINT MONO (2005 4012);
FORCEPROP 1 LASTPIN (2000 3850) $PN 2
J 0
(2005 3860);
DISPLAY 0.787234 (2005 3860);
PAINT MONO (2005 3860);
FORCEPROP 1 LAST MATERIAL CHIP
J 0
(2040 3875);
DISPLAY 0.638298 (2040 3875);
FORCEPROP 1 LAST WATTAGE 1/16W
J 0
(2040 3925);
DISPLAY 0.638298 (2040 3925);
FORCEPROP 1 LAST VALUE 100K
J 0
(2045 4025);
DISPLAY 0.638298 (2045 4025);
FORCEPROP 1 LAST TOLERANCE 1%
J 0
(2045 3975);
DISPLAY 0.638298 (2045 3975);
FORCEPROP 1 LAST PACK_TYPE 0402LF
J 0
(2040 3825);
DISPLAY 0.638298 (2040 3825);
FORCEPROP 2 LAST CDS_LIB pure_quanta
J 0
(2000 3950);
DISPLAY INVISIBLE (2000 3950);
FORCEPROP 1 LAST PATH I158
J 0
(2050 4125);
DISPLAY 0.978723 (2050 4125);
PAINT WHITE (2050 4125);
DISPLAY INVISIBLE (2050 4125);
FORCEPROP 1 LAST PART_NUMBER CS41002FB09
J 0
(2040 3775);
DISPLAY 0.638298 (2040 3775);
DISPLAY INVISIBLE (2040 3775);
FORCEADD MOSFET_NCH_DUAL..2
(1950 3500);
FORCEPROP 1 LAST LOCATION Q96
J 0
(2101 3476);
DISPLAY 0.723404 (2101 3476);
PAINT GREEN (2101 3476);
FORCEPROP 0 LAST $SEC 2
J 0
(2125 3625);
DISPLAY 0.680851 (2125 3625);
PAINT MONO (2125 3625);
DISPLAY INVISIBLE (2125 3625);
FORCEPROP 0 LAST CDS_SEC 2
J 0
(2125 3625);
DISPLAY 1.021277 (2125 3625);
DISPLAY INVISIBLE (2125 3625);
FORCEPROP 0 LASTPIN (2000 3700) $PN 3
R 1
J 0
(1990 3710);
DISPLAY 0.680851 (1990 3710);
PAINT MONO (1990 3710);
FORCEPROP 0 LASTPIN (1750 3450) $PN 5
J 2
(1740 3460);
DISPLAY 0.680851 (1740 3460);
PAINT MONO (1740 3460);
FORCEPROP 0 LASTPIN (2000 3300) $PN 4
R 1
J 2
(1990 3290);
DISPLAY 0.680851 (1990 3290);
PAINT MONO (1990 3290);
FORCEPROP 1 LAST MATERIAL IC
J 0
(2101 3351);
DISPLAY 0.723404 (2101 3351);
PAINT GREEN (2101 3351);
FORCEPROP 2 LAST VALUE PJT138K
J 0
(2125 3525);
DISPLAY 1.021277 (2125 3525);
FORCEPROP 2 LAST PART_TYPE SMLF
J 0
(2125 3575);
DISPLAY 1.021277 (2125 3575);
FORCEPROP 1 LAST CDS_LMAN_SYM_OUTLINE -150,150,150,-150
J 0
(1950 3500);
DISPLAY 0.468085 (1950 3500);
PAINT GREEN (1950 3500);
DISPLAY INVISIBLE (1950 3500);
FORCEPROP 1 LAST NEEDS_NO_SIZE TRUE
J 0
(2100 3391);
DISPLAY 0.468085 (2100 3391);
PAINT GREEN (2100 3391);
DISPLAY INVISIBLE (2100 3391);
FORCEPROP 2 LAST CDS_LIB pure_quanta
J 0
(1950 3500);
DISPLAY INVISIBLE (1950 3500);
FORCEPROP 1 LAST PATH I159
J 0
(2100 3350);
DISPLAY 0.723404 (2100 3350);
PAINT GREEN (2100 3350);
DISPLAY INVISIBLE (2100 3350);
FORCEPROP 1 LAST PART_NUMBER BAM138K0003
J 0
(2101 3406);
DISPLAY 0.723404 (2101 3406);
PAINT GREEN (2101 3406);
DISPLAY INVISIBLE (2101 3406);
FORCEADD UNIVERSAL_POWER..1
(-3475 6750);
FORCEPROP 3 LASTPIN (-3475 6700) SIG_NAME P3V3_AUX\g
J 0
(-3465 6710);
DISPLAY 0.659574 (-3465 6710);
PAINT MONO (-3465 6710);
DISPLAY INVISIBLE (-3465 6710);
FORCEPROP 1 LAST HDL_POWER P3V3_AUX
J 1
(-3475 6800);
DISPLAY 0.872340 (-3475 6800);
PAINT GREEN (-3475 6800);
FORCEPROP 2 LAST CDS_LIB pure_quanta_power
J 0
(-3475 6750);
PAINT MONO (-3475 6750);
DISPLAY INVISIBLE (-3475 6750);
FORCEPROP 1 LAST PATH I16
J 0
(-3425 6775);
DISPLAY 0.872340 (-3425 6775);
PAINT AQUA (-3425 6775);
DISPLAY INVISIBLE (-3425 6775);
FORCEADD UNIVERSAL_GND..1
(2000 3125);
FORCEPROP 3 LASTPIN (2000 3175) SIG_NAME GND\g
J 0
(2010 3185);
DISPLAY 0.659574 (2010 3185);
PAINT MONO (2010 3185);
DISPLAY INVISIBLE (2010 3185);
FORCEPROP 2 LAST CDS_LIB pure_quanta_power
J 0
(2000 3125);
DISPLAY INVISIBLE (2000 3125);
FORCEPROP 1 LAST HDL_POWER GND
J 1
(2025 3050);
DISPLAY 0.872340 (2025 3050);
PAINT GREEN (2025 3050);
DISPLAY INVISIBLE (2025 3050);
FORCEPROP 1 LAST PATH I160
J 0
(2075 3125);
DISPLAY 0.872340 (2075 3125);
PAINT AQUA (2075 3125);
DISPLAY INVISIBLE (2075 3125);
FORCEADD UNIVERSAL_POWER..1
(1075 4000);
FORCEPROP 3 LASTPIN (1075 3950) SIG_NAME P3V3_AUX\g
J 0
(1085 3960);
DISPLAY 0.659574 (1085 3960);
PAINT MONO (1085 3960);
DISPLAY INVISIBLE (1085 3960);
FORCEPROP 1 LAST HDL_POWER P3V3_AUX
J 1
(1075 4050);
DISPLAY 0.872340 (1075 4050);
PAINT GREEN (1075 4050);
FORCEPROP 2 LAST CDS_LIB pure_quanta_power
J 0
(1075 4000);
PAINT MONO (1075 4000);
DISPLAY INVISIBLE (1075 4000);
FORCEPROP 1 LAST PATH I161
J 0
(1125 4025);
DISPLAY 0.872340 (1125 4025);
PAINT AQUA (1125 4025);
DISPLAY INVISIBLE (1125 4025);
FORCEADD Q_RES..2
(1075 3700);
FORCEPROP 1 LAST LOCATION R3320
J 0
(1120 3825);
DISPLAY 0.638298 (1120 3825);
FORCEPROP 2 LAST $SEC 1
J 0
(1125 3925);
DISPLAY 0.680851 (1125 3925);
PAINT MONO (1125 3925);
DISPLAY INVISIBLE (1125 3925);
FORCEPROP 2 LAST CDS_SEC 1
J 0
(1125 3925);
DISPLAY 1.021277 (1125 3925);
DISPLAY INVISIBLE (1125 3925);
FORCEPROP 1 LASTPIN (1075 3800) $PN 1
J 0
(1080 3762);
DISPLAY 0.787234 (1080 3762);
FORCEPROP 1 LASTPIN (1075 3600) $PN 2
J 0
(1080 3610);
DISPLAY 0.787234 (1080 3610);
FORCEPROP 1 LAST MATERIAL CHIP
J 0
(1115 3625);
DISPLAY 0.638298 (1115 3625);
FORCEPROP 1 LAST VALUE 4.7K
J 0
(1120 3775);
DISPLAY 0.638298 (1120 3775);
FORCEPROP 1 LAST PACK_TYPE 0402LF
J 0
(1115 3575);
DISPLAY 0.638298 (1115 3575);
FORCEPROP 1 LAST TOLERANCE 5%
J 0
(1120 3725);
DISPLAY 0.638298 (1120 3725);
FORCEPROP 1 LAST WATTAGE 1/16W
J 0
(1115 3675);
DISPLAY 0.638298 (1115 3675);
FORCEPROP 2 LAST CDS_LIB pure_quanta
J 0
(1075 3700);
PAINT MONO (1075 3700);
DISPLAY INVISIBLE (1075 3700);
FORCEPROP 1 LAST PATH I162
J 0
(1125 3875);
DISPLAY 0.978723 (1125 3875);
PAINT WHITE (1125 3875);
DISPLAY INVISIBLE (1125 3875);
FORCEPROP 1 LAST PART_NUMBER CS24702JB10
J 0
(1115 3525);
DISPLAY 0.638298 (1115 3525);
DISPLAY INVISIBLE (1115 3525);
FORCEADD UNIVERSAL_GND..1
(1075 2850);
FORCEPROP 3 LASTPIN (1075 2900) SIG_NAME GND\g
J 0
(1085 2910);
DISPLAY 0.659574 (1085 2910);
PAINT MONO (1085 2910);
DISPLAY INVISIBLE (1085 2910);
FORCEPROP 2 LAST CDS_LIB pure_quanta_power
J 0
(1075 2850);
DISPLAY INVISIBLE (1075 2850);
FORCEPROP 1 LAST HDL_POWER GND
J 1
(1100 2775);
DISPLAY 0.872340 (1100 2775);
PAINT GREEN (1100 2775);
DISPLAY INVISIBLE (1100 2775);
FORCEPROP 1 LAST PATH I163
J 0
(1150 2850);
DISPLAY 0.872340 (1150 2850);
PAINT AQUA (1150 2850);
DISPLAY INVISIBLE (1150 2850);
FORCEADD UNIVERSAL_POWER..1
(-175 3700);
FORCEPROP 3 LASTPIN (-175 3650) SIG_NAME P3V3_AUX\g
J 0
(-165 3660);
DISPLAY 0.659574 (-165 3660);
PAINT MONO (-165 3660);
DISPLAY INVISIBLE (-165 3660);
FORCEPROP 1 LAST HDL_POWER P3V3_AUX
J 1
(-175 3750);
DISPLAY 0.872340 (-175 3750);
PAINT GREEN (-175 3750);
FORCEPROP 2 LAST CDS_LIB pure_quanta_power
J 0
(-175 3700);
PAINT MONO (-175 3700);
DISPLAY INVISIBLE (-175 3700);
FORCEPROP 1 LAST PATH I164
J 0
(-125 3725);
DISPLAY 0.872340 (-125 3725);
PAINT AQUA (-125 3725);
DISPLAY INVISIBLE (-125 3725);
FORCEADD UNIVERSAL_GND..1
(-150 2775);
FORCEPROP 3 LASTPIN (-150 2825) SIG_NAME GND\g
J 0
(-140 2835);
DISPLAY 0.659574 (-140 2835);
PAINT MONO (-140 2835);
DISPLAY INVISIBLE (-140 2835);
FORCEPROP 2 LAST CDS_LIB pure_quanta_power
J 0
(-150 2775);
DISPLAY INVISIBLE (-150 2775);
FORCEPROP 1 LAST HDL_POWER GND
J 1
(-125 2700);
DISPLAY 0.872340 (-125 2700);
PAINT GREEN (-125 2700);
DISPLAY INVISIBLE (-125 2700);
FORCEPROP 1 LAST PATH I167
J 0
(-75 2775);
DISPLAY 0.872340 (-75 2775);
PAINT AQUA (-75 2775);
DISPLAY INVISIBLE (-75 2775);
FORCEADD OFFPAGE..4
R 2
(-450 3175);
FORCEPROP 2 LAST $XR0 122 
J 0
(-732 3175);
DISPLAY 0.638298 (-732 3175);
PAINT MONO (-732 3175);
FORCEPROP 2 LAST CDS_LIB standard
J 0
(-450 3175);
DISPLAY INVISIBLE (-450 3175);
FORCEPROP 1 LAST OFFPAGE TRUE
J 2
(-775 3050);
DISPLAY 0.872340 (-775 3050);
PAINT GREEN (-775 3050);
DISPLAY INVISIBLE (-775 3050);
FORCEPROP 1 LAST COMMENT_BODY TRUE
J 2
(-425 3075);
DISPLAY 0.872340 (-425 3075);
PAINT GREEN (-425 3075);
DISPLAY INVISIBLE (-425 3075);
FORCEPROP 2 LAST PATH I168
J 0
(-725 3225);
DISPLAY 1.021277 (-725 3225);
DISPLAY INVISIBLE (-725 3225);
FORCEADD OFFPAGE..2
(2100 2950);
FORCEPROP 2 LAST $XR0 234 
J 0
(2289 2950);
DISPLAY 0.638298 (2289 2950);
PAINT MONO (2289 2950);
FORCEPROP 2 LAST CDS_LIB standard
J 0
(2100 2950);
DISPLAY INVISIBLE (2100 2950);
FORCEPROP 1 LAST OFFPAGE TRUE
J 0
(2425 2825);
DISPLAY 0.872340 (2425 2825);
PAINT AQUA (2425 2825);
DISPLAY INVISIBLE (2425 2825);
FORCEPROP 1 LAST COMMENT_BODY TRUE
J 0
(2055 2855);
DISPLAY 0.872340 (2055 2855);
PAINT GREEN (2055 2855);
DISPLAY INVISIBLE (2055 2855);
FORCEPROP 2 LAST PATH I169
J 0
(2275 3025);
DISPLAY 1.021277 (2275 3025);
DISPLAY INVISIBLE (2275 3025);
FORCEADD Q_RES..2
(-175 3400);
FORCEPROP 1 LAST LOCATION R3318
J 0
(-130 3525);
DISPLAY 0.978723 (-130 3525);
FORCEPROP 0 LAST $SEC 1
J 0
(-125 3575);
DISPLAY 0.680851 (-125 3575);
PAINT MONO (-125 3575);
DISPLAY INVISIBLE (-125 3575);
FORCEPROP 0 LAST CDS_SEC 1
J 0
(-125 3575);
DISPLAY 1.021277 (-125 3575);
DISPLAY INVISIBLE (-125 3575);
FORCEPROP 1 LASTPIN (-175 3500) $PN 1
J 0
(-170 3462);
DISPLAY 0.787234 (-170 3462);
PAINT MONO (-170 3462);
FORCEPROP 1 LASTPIN (-175 3300) $PN 2
J 0
(-170 3310);
DISPLAY 0.787234 (-170 3310);
PAINT MONO (-170 3310);
FORCEPROP 1 LAST VALUE 100K
J 0
(-130 3475);
DISPLAY 0.510638 (-130 3475);
FORCEPROP 1 LAST MATERIAL EMPTY
J 0
(-135 3325);
DISPLAY 0.510638 (-135 3325);
FORCEPROP 1 LAST TOLERANCE 1%
J 0
(-130 3425);
DISPLAY 0.510638 (-130 3425);
FORCEPROP 1 LAST WATTAGE 1/16W
J 0
(-135 3375);
DISPLAY 0.510638 (-135 3375);
FORCEPROP 1 LAST PACK_TYPE 0402LF
J 0
(-135 3225);
DISPLAY 0.510638 (-135 3225);
FORCEPROP 2 LAST CDS_LIB pure_quanta
J 0
(-175 3400);
DISPLAY INVISIBLE (-175 3400);
FORCEPROP 1 LAST PATH I171
J 0
(-125 3575);
DISPLAY 0.978723 (-125 3575);
PAINT WHITE (-125 3575);
DISPLAY INVISIBLE (-125 3575);
FORCEPROP 1 LAST PART_NUMBER CS41002FB09
J 0
(-135 3275);
DISPLAY 0.510638 (-135 3275);
DISPLAY INVISIBLE (-135 3275);
FORCEADD Q_RES..2
(-150 2975);
FORCEPROP 1 LAST LOCATION R3511
J 0
(-105 3100);
DISPLAY 0.978723 (-105 3100);
FORCEPROP 0 LAST $SEC 1
J 0
(-100 3150);
DISPLAY 0.680851 (-100 3150);
PAINT MONO (-100 3150);
DISPLAY INVISIBLE (-100 3150);
FORCEPROP 0 LAST CDS_SEC 1
J 0
(-100 3150);
DISPLAY 1.021277 (-100 3150);
DISPLAY INVISIBLE (-100 3150);
FORCEPROP 1 LASTPIN (-150 3075) $PN 1
J 0
(-145 3037);
DISPLAY 0.787234 (-145 3037);
PAINT MONO (-145 3037);
FORCEPROP 1 LASTPIN (-150 2875) $PN 2
J 0
(-145 2885);
DISPLAY 0.787234 (-145 2885);
PAINT MONO (-145 2885);
FORCEPROP 1 LAST VALUE 54.9K
J 0
(-105 3050);
DISPLAY 0.787234 (-105 3050);
FORCEPROP 1 LAST MATERIAL CHIP
J 0
(-110 2900);
DISPLAY 0.787234 (-110 2900);
FORCEPROP 1 LAST WATTAGE 1/16W
J 0
(-110 2950);
DISPLAY 0.787234 (-110 2950);
FORCEPROP 1 LAST TOLERANCE 1%
J 0
(-105 3000);
DISPLAY 0.787234 (-105 3000);
FORCEPROP 1 LAST PACK_TYPE 0402LF
J 0
(-110 2800);
DISPLAY 0.787234 (-110 2800);
FORCEPROP 2 LAST CDS_LIB pure_quanta
J 0
(-150 2975);
DISPLAY INVISIBLE (-150 2975);
FORCEPROP 1 LAST PATH I172
J 0
(-100 3150);
DISPLAY 0.978723 (-100 3150);
PAINT WHITE (-100 3150);
DISPLAY INVISIBLE (-100 3150);
FORCEPROP 1 LAST PART_NUMBER CS35492FB03
J 0
(-110 2850);
DISPLAY 0.787234 (-110 2850);
DISPLAY INVISIBLE (-110 2850);
FORCEADD Q_RES..2
(-125 5900);
FORCEPROP 1 LAST LOCATION R3513
J 0
(-80 6025);
DISPLAY 0.978723 (-80 6025);
FORCEPROP 0 LAST $SEC 1
J 0
(-75 6075);
DISPLAY 0.680851 (-75 6075);
PAINT MONO (-75 6075);
DISPLAY INVISIBLE (-75 6075);
FORCEPROP 0 LAST CDS_SEC 1
J 0
(-75 6075);
DISPLAY 1.021277 (-75 6075);
DISPLAY INVISIBLE (-75 6075);
FORCEPROP 1 LASTPIN (-125 6000) $PN 1
J 0
(-120 5962);
DISPLAY 0.787234 (-120 5962);
PAINT MONO (-120 5962);
FORCEPROP 1 LASTPIN (-125 5800) $PN 2
J 0
(-120 5810);
DISPLAY 0.787234 (-120 5810);
PAINT MONO (-120 5810);
FORCEPROP 1 LAST PACK_TYPE 0402LF
J 0
(-85 5725);
DISPLAY 0.787234 (-85 5725);
FORCEPROP 1 LAST TOLERANCE 1%
J 0
(-80 5925);
DISPLAY 0.787234 (-80 5925);
FORCEPROP 1 LAST VALUE 54.9K
J 0
(-80 5975);
DISPLAY 0.787234 (-80 5975);
FORCEPROP 1 LAST MATERIAL CHIP
J 0
(-85 5825);
DISPLAY 0.787234 (-85 5825);
FORCEPROP 1 LAST WATTAGE 1/16W
J 0
(-85 5875);
DISPLAY 0.787234 (-85 5875);
FORCEPROP 2 LAST CDS_LIB pure_quanta
J 0
(-125 5900);
DISPLAY INVISIBLE (-125 5900);
FORCEPROP 1 LAST PATH I173
J 0
(-75 6075);
DISPLAY 0.978723 (-75 6075);
PAINT WHITE (-75 6075);
DISPLAY INVISIBLE (-75 6075);
FORCEPROP 1 LAST PART_NUMBER CS35492FB03
J 0
(-85 5775);
DISPLAY 0.787234 (-85 5775);
DISPLAY INVISIBLE (-85 5775);
FORCEADD Q_RES..2
(-150 6325);
FORCEPROP 1 LAST LOCATION R3512
J 0
(-105 6450);
DISPLAY 0.978723 (-105 6450);
FORCEPROP 0 LAST $SEC 1
J 0
(-100 6500);
DISPLAY 0.680851 (-100 6500);
PAINT MONO (-100 6500);
DISPLAY INVISIBLE (-100 6500);
FORCEPROP 0 LAST CDS_SEC 1
J 0
(-100 6500);
DISPLAY 1.021277 (-100 6500);
DISPLAY INVISIBLE (-100 6500);
FORCEPROP 1 LASTPIN (-150 6425) $PN 1
J 0
(-145 6387);
DISPLAY 0.787234 (-145 6387);
PAINT MONO (-145 6387);
FORCEPROP 1 LASTPIN (-150 6225) $PN 2
J 0
(-145 6235);
DISPLAY 0.787234 (-145 6235);
PAINT MONO (-145 6235);
FORCEPROP 1 LAST MATERIAL EMPTY
J 0
(-110 6250);
DISPLAY 0.510638 (-110 6250);
FORCEPROP 1 LAST VALUE 100K
J 0
(-105 6400);
DISPLAY 0.510638 (-105 6400);
FORCEPROP 1 LAST TOLERANCE 1%
J 0
(-105 6350);
DISPLAY 0.510638 (-105 6350);
FORCEPROP 1 LAST WATTAGE 1/16W
J 0
(-110 6300);
DISPLAY 0.510638 (-110 6300);
FORCEPROP 1 LAST PACK_TYPE 0402LF
J 0
(-110 6150);
DISPLAY 0.510638 (-110 6150);
FORCEPROP 2 LAST CDS_LIB pure_quanta
J 0
(-150 6325);
DISPLAY INVISIBLE (-150 6325);
FORCEPROP 1 LAST PATH I174
J 0
(-100 6500);
DISPLAY 0.978723 (-100 6500);
PAINT WHITE (-100 6500);
DISPLAY INVISIBLE (-100 6500);
FORCEPROP 1 LAST PART_NUMBER CS41002FB09
J 0
(-110 6200);
DISPLAY 0.510638 (-110 6200);
DISPLAY INVISIBLE (-110 6200);
FORCEADD Q_RES..2
(-125 4950);
FORCEPROP 1 LAST LOCATION R3514
J 0
(-80 5075);
DISPLAY 0.978723 (-80 5075);
FORCEPROP 0 LAST $SEC 1
J 0
(-75 5125);
DISPLAY 0.680851 (-75 5125);
PAINT MONO (-75 5125);
DISPLAY INVISIBLE (-75 5125);
FORCEPROP 0 LAST CDS_SEC 1
J 0
(-75 5125);
DISPLAY 1.021277 (-75 5125);
DISPLAY INVISIBLE (-75 5125);
FORCEPROP 1 LASTPIN (-125 5050) $PN 1
J 0
(-120 5012);
DISPLAY 0.787234 (-120 5012);
PAINT MONO (-120 5012);
FORCEPROP 1 LASTPIN (-125 4850) $PN 2
J 0
(-120 4860);
DISPLAY 0.787234 (-120 4860);
PAINT MONO (-120 4860);
FORCEPROP 1 LAST PACK_TYPE 0402LF
J 0
(-85 4775);
DISPLAY 0.787234 (-85 4775);
FORCEPROP 1 LAST VALUE 54.9K
J 0
(-80 5025);
DISPLAY 0.787234 (-80 5025);
FORCEPROP 1 LAST TOLERANCE 1%
J 0
(-80 4975);
DISPLAY 0.787234 (-80 4975);
FORCEPROP 1 LAST MATERIAL CHIP
J 0
(-85 4875);
DISPLAY 0.787234 (-85 4875);
FORCEPROP 1 LAST WATTAGE 1/16W
J 0
(-85 4925);
DISPLAY 0.787234 (-85 4925);
FORCEPROP 2 LAST CDS_LIB pure_quanta
J 0
(-125 4950);
DISPLAY INVISIBLE (-125 4950);
FORCEPROP 1 LAST PATH I175
J 0
(-75 5125);
DISPLAY 0.978723 (-75 5125);
PAINT WHITE (-75 5125);
DISPLAY INVISIBLE (-75 5125);
FORCEPROP 1 LAST PART_NUMBER CS35492FB03
J 0
(-85 4825);
DISPLAY 0.787234 (-85 4825);
DISPLAY INVISIBLE (-85 4825);
FORCEADD Q_RES..2
(-4675 3250);
FORCEPROP 1 LAST LOCATION R3510
J 0
(-4630 3375);
DISPLAY 0.978723 (-4630 3375);
FORCEPROP 0 LAST $SEC 1
J 0
(-4625 3425);
DISPLAY 0.680851 (-4625 3425);
PAINT MONO (-4625 3425);
DISPLAY INVISIBLE (-4625 3425);
FORCEPROP 0 LAST CDS_SEC 1
J 0
(-4625 3425);
DISPLAY 1.021277 (-4625 3425);
DISPLAY INVISIBLE (-4625 3425);
FORCEPROP 1 LASTPIN (-4675 3350) $PN 1
J 0
(-4670 3312);
DISPLAY 0.787234 (-4670 3312);
PAINT MONO (-4670 3312);
FORCEPROP 1 LASTPIN (-4675 3150) $PN 2
J 0
(-4670 3160);
DISPLAY 0.787234 (-4670 3160);
PAINT MONO (-4670 3160);
FORCEPROP 1 LAST TOLERANCE 1%
J 0
(-4630 3275);
DISPLAY 0.787234 (-4630 3275);
FORCEPROP 1 LAST VALUE 54.9K
J 0
(-4630 3325);
DISPLAY 0.787234 (-4630 3325);
FORCEPROP 1 LAST WATTAGE 1/16W
J 0
(-4635 3225);
DISPLAY 0.787234 (-4635 3225);
FORCEPROP 1 LAST MATERIAL CHIP
J 0
(-4635 3175);
DISPLAY 0.787234 (-4635 3175);
FORCEPROP 1 LAST PACK_TYPE 0402LF
J 0
(-4635 3075);
DISPLAY 0.787234 (-4635 3075);
FORCEPROP 2 LAST CDS_LIB pure_quanta
J 0
(-4675 3250);
DISPLAY INVISIBLE (-4675 3250);
FORCEPROP 1 LAST PATH I176
J 0
(-4625 3425);
DISPLAY 0.978723 (-4625 3425);
PAINT WHITE (-4625 3425);
DISPLAY INVISIBLE (-4625 3425);
FORCEPROP 1 LAST PART_NUMBER CS35492FB03
J 0
(-4635 3125);
DISPLAY 0.787234 (-4635 3125);
DISPLAY INVISIBLE (-4635 3125);
FORCEADD Q_RES..2
R 2
(-2375 8125);
FORCEPROP 1 LAST LOCATION R2920
J 2
(-2420 8250);
DISPLAY 0.787234 (-2420 8250);
FORCEPROP 0 LAST $SEC 1
J 0
(-2400 8300);
DISPLAY 0.680851 (-2400 8300);
PAINT MONO (-2400 8300);
DISPLAY INVISIBLE (-2400 8300);
FORCEPROP 0 LAST CDS_SEC 1
J 0
(-2400 8300);
DISPLAY 0.680851 (-2400 8300);
DISPLAY INVISIBLE (-2400 8300);
FORCEPROP 1 LASTPIN (-2375 8225) $PN 1
J 2
(-2380 8187);
DISPLAY 0.787234 (-2380 8187);
PAINT MONO (-2380 8187);
FORCEPROP 1 LASTPIN (-2375 8025) $PN 2
J 2
(-2380 8035);
DISPLAY 0.787234 (-2380 8035);
PAINT MONO (-2380 8035);
FORCEPROP 1 LAST TOLERANCE 1%
J 2
(-2420 8150);
DISPLAY 0.787234 (-2420 8150);
FORCEPROP 1 LAST MATERIAL CHIP
J 2
(-2415 8050);
DISPLAY 0.787234 (-2415 8050);
FORCEPROP 1 LAST WATTAGE 1/16W
J 2
(-2415 8100);
DISPLAY 0.787234 (-2415 8100);
FORCEPROP 1 LAST PACK_TYPE 0402LF
J 2
(-2415 7950);
DISPLAY 0.787234 (-2415 7950);
FORCEPROP 1 LAST VALUE 100K
J 2
(-2420 8200);
DISPLAY 0.787234 (-2420 8200);
FORCEPROP 2 LAST CDS_LIB pure_quanta
J 2
(-2375 8125);
DISPLAY INVISIBLE (-2375 8125);
FORCEPROP 1 LAST PATH I177
J 2
(-2425 8300);
DISPLAY 0.978723 (-2425 8300);
PAINT WHITE (-2425 8300);
DISPLAY INVISIBLE (-2425 8300);
FORCEPROP 1 LAST PART_NUMBER CS41002FB09
J 2
(-2415 8000);
DISPLAY 0.787234 (-2415 8000);
DISPLAY INVISIBLE (-2415 8000);
FORCEADD Q_RES..2
R 2
(-2500 3800);
FORCEPROP 1 LAST LOCATION R3030
J 2
(-2545 3925);
DISPLAY 0.787234 (-2545 3925);
FORCEPROP 0 LAST $SEC 1
J 0
(-2525 3975);
DISPLAY 0.680851 (-2525 3975);
PAINT MONO (-2525 3975);
DISPLAY INVISIBLE (-2525 3975);
FORCEPROP 0 LAST CDS_SEC 1
J 0
(-2525 3975);
DISPLAY 0.680851 (-2525 3975);
DISPLAY INVISIBLE (-2525 3975);
FORCEPROP 1 LASTPIN (-2500 3900) $PN 1
J 2
(-2505 3862);
DISPLAY 0.787234 (-2505 3862);
PAINT MONO (-2505 3862);
FORCEPROP 1 LASTPIN (-2500 3700) $PN 2
J 2
(-2505 3710);
DISPLAY 0.787234 (-2505 3710);
PAINT MONO (-2505 3710);
FORCEPROP 1 LAST VALUE 100K
J 2
(-2545 3875);
DISPLAY 0.787234 (-2545 3875);
FORCEPROP 1 LAST TOLERANCE 1%
J 2
(-2545 3825);
DISPLAY 0.787234 (-2545 3825);
FORCEPROP 1 LAST WATTAGE 1/16W
J 2
(-2540 3775);
DISPLAY 0.787234 (-2540 3775);
FORCEPROP 1 LAST MATERIAL CHIP
J 2
(-2540 3725);
DISPLAY 0.787234 (-2540 3725);
FORCEPROP 1 LAST PACK_TYPE 0402LF
J 2
(-2540 3625);
DISPLAY 0.787234 (-2540 3625);
FORCEPROP 2 LAST CDS_LIB pure_quanta
J 2
(-2500 3800);
DISPLAY INVISIBLE (-2500 3800);
FORCEPROP 1 LAST PATH I178
J 2
(-2550 3975);
DISPLAY 0.978723 (-2550 3975);
PAINT WHITE (-2550 3975);
DISPLAY INVISIBLE (-2550 3975);
FORCEPROP 1 LAST PART_NUMBER CS41002FB09
J 2
(-2540 3675);
DISPLAY 0.787234 (-2540 3675);
DISPLAY INVISIBLE (-2540 3675);
FORCEADD Q_RES..2
R 2
(2050 5500);
FORCEPROP 1 LAST LOCATION R3035
J 2
(2005 5625);
DISPLAY 0.978723 (2005 5625);
FORCEPROP 2 LAST SEC 1
J 0
(2000 5725);
DISPLAY 0.680851 (2000 5725);
PAINT MONO (2000 5725);
DISPLAY INVISIBLE (2000 5725);
FORCEPROP 1 LASTPIN (2050 5600) $PN 1
J 2
(2045 5562);
DISPLAY 0.787234 (2045 5562);
PAINT MONO (2045 5562);
FORCEPROP 1 LASTPIN (2050 5400) $PN 2
J 2
(2045 5410);
DISPLAY 0.787234 (2045 5410);
PAINT MONO (2045 5410);
FORCEPROP 1 LAST VALUE 100K
J 2
(2005 5575);
DISPLAY 0.787234 (2005 5575);
FORCEPROP 1 LAST WATTAGE 1/16W
J 2
(2010 5475);
DISPLAY 0.787234 (2010 5475);
FORCEPROP 1 LAST MATERIAL CHIP
J 2
(2010 5425);
DISPLAY 0.787234 (2010 5425);
FORCEPROP 1 LAST TOLERANCE 1%
J 2
(2005 5525);
DISPLAY 0.787234 (2005 5525);
FORCEPROP 1 LAST PACK_TYPE 0402LF
J 2
(2010 5325);
DISPLAY 0.787234 (2010 5325);
FORCEPROP 2 LAST SEC_TYPE 0402LF
J 0
(2000 5725);
DISPLAY 0.680851 (2000 5725);
DISPLAY INVISIBLE (2000 5725);
FORCEPROP 2 LAST CDS_LIB pure_quanta
J 0
(2050 5500);
DISPLAY INVISIBLE (2050 5500);
FORCEPROP 1 LAST PATH I179
J 2
(2000 5675);
DISPLAY 0.978723 (2000 5675);
PAINT WHITE (2000 5675);
DISPLAY INVISIBLE (2000 5675);
FORCEPROP 1 LAST PART_NUMBER CS41002FB09
J 2
(2010 5375);
DISPLAY 0.787234 (2010 5375);
DISPLAY INVISIBLE (2010 5375);
FORCEADD Q_RES..2
(-3475 6450);
FORCEPROP 1 LAST LOCATION R2834
J 0
(-3430 6575);
DISPLAY 0.638298 (-3430 6575);
FORCEPROP 2 LAST $SEC 1
J 0
(-3425 6675);
DISPLAY 0.680851 (-3425 6675);
PAINT MONO (-3425 6675);
DISPLAY INVISIBLE (-3425 6675);
FORCEPROP 2 LAST CDS_SEC 1
J 0
(-3425 6675);
DISPLAY 1.021277 (-3425 6675);
DISPLAY INVISIBLE (-3425 6675);
FORCEPROP 1 LASTPIN (-3475 6550) $PN 1
J 0
(-3470 6512);
DISPLAY 0.787234 (-3470 6512);
FORCEPROP 1 LASTPIN (-3475 6350) $PN 2
J 0
(-3470 6360);
DISPLAY 0.787234 (-3470 6360);
FORCEPROP 1 LAST WATTAGE 1/16W
J 0
(-3435 6425);
DISPLAY 0.638298 (-3435 6425);
FORCEPROP 1 LAST TOLERANCE 5%
J 0
(-3430 6475);
DISPLAY 0.638298 (-3430 6475);
FORCEPROP 1 LAST PACK_TYPE 0402LF
J 0
(-3435 6325);
DISPLAY 0.638298 (-3435 6325);
FORCEPROP 1 LAST MATERIAL CHIP
J 0
(-3435 6375);
DISPLAY 0.638298 (-3435 6375);
FORCEPROP 1 LAST VALUE 4.7K
J 0
(-3430 6525);
DISPLAY 0.638298 (-3430 6525);
FORCEPROP 2 LAST CDS_LIB pure_quanta
J 0
(-3475 6450);
PAINT MONO (-3475 6450);
DISPLAY INVISIBLE (-3475 6450);
FORCEPROP 1 LAST PATH I18
J 0
(-3425 6625);
DISPLAY 0.978723 (-3425 6625);
PAINT WHITE (-3425 6625);
DISPLAY INVISIBLE (-3425 6625);
FORCEPROP 1 LAST PART_NUMBER CS24702JB10
J 0
(-3435 6275);
DISPLAY 0.638298 (-3435 6275);
DISPLAY INVISIBLE (-3435 6275);
FORCEADD Q_RES..2
R 2
(-2500 5350);
FORCEPROP 1 LAST LOCATION R2933
J 2
(-2545 5475);
DISPLAY 0.978723 (-2545 5475);
FORCEPROP 0 LAST $SEC 1
J 0
(-2525 5525);
DISPLAY 0.680851 (-2525 5525);
PAINT MONO (-2525 5525);
DISPLAY INVISIBLE (-2525 5525);
FORCEPROP 0 LAST CDS_SEC 1
J 0
(-2525 5525);
DISPLAY 0.680851 (-2525 5525);
DISPLAY INVISIBLE (-2525 5525);
FORCEPROP 1 LASTPIN (-2500 5450) $PN 1
J 2
(-2505 5412);
DISPLAY 0.787234 (-2505 5412);
PAINT MONO (-2505 5412);
FORCEPROP 1 LASTPIN (-2500 5250) $PN 2
J 2
(-2505 5260);
DISPLAY 0.787234 (-2505 5260);
PAINT MONO (-2505 5260);
FORCEPROP 1 LAST TOLERANCE 1%
J 2
(-2545 5375);
DISPLAY 0.787234 (-2545 5375);
FORCEPROP 1 LAST WATTAGE 1/16W
J 2
(-2540 5325);
DISPLAY 0.787234 (-2540 5325);
FORCEPROP 1 LAST PACK_TYPE 0402LF
J 2
(-2540 5175);
DISPLAY 0.787234 (-2540 5175);
FORCEPROP 1 LAST VALUE 100K
J 2
(-2545 5425);
DISPLAY 0.787234 (-2545 5425);
FORCEPROP 1 LAST MATERIAL CHIP
J 2
(-2540 5275);
DISPLAY 0.787234 (-2540 5275);
FORCEPROP 2 LAST CDS_LIB pure_quanta
J 0
(-2500 5350);
DISPLAY INVISIBLE (-2500 5350);
FORCEPROP 1 LAST PATH I180
J 2
(-2550 5525);
DISPLAY 0.978723 (-2550 5525);
PAINT WHITE (-2550 5525);
DISPLAY INVISIBLE (-2550 5525);
FORCEPROP 1 LAST PART_NUMBER CS41002FB09
J 2
(-2540 5225);
DISPLAY 0.787234 (-2540 5225);
DISPLAY INVISIBLE (-2540 5225);
FORCEADD Q_RES..2
(-3450 5100);
FORCEPROP 1 LAST LOCATION R2836
J 0
(-3405 5225);
DISPLAY 0.638298 (-3405 5225);
FORCEPROP 2 LAST $SEC 1
J 0
(-3400 5325);
DISPLAY 0.680851 (-3400 5325);
PAINT MONO (-3400 5325);
DISPLAY INVISIBLE (-3400 5325);
FORCEPROP 2 LAST CDS_SEC 1
J 0
(-3400 5325);
DISPLAY 1.021277 (-3400 5325);
DISPLAY INVISIBLE (-3400 5325);
FORCEPROP 1 LASTPIN (-3450 5200) $PN 1
J 0
(-3445 5162);
DISPLAY 0.787234 (-3445 5162);
FORCEPROP 1 LASTPIN (-3450 5000) $PN 2
J 0
(-3445 5010);
DISPLAY 0.787234 (-3445 5010);
FORCEPROP 1 LAST TOLERANCE 5%
J 0
(-3405 5125);
DISPLAY 0.638298 (-3405 5125);
FORCEPROP 1 LAST WATTAGE 1/16W
J 0
(-3410 5075);
DISPLAY 0.638298 (-3410 5075);
FORCEPROP 1 LAST MATERIAL CHIP
J 0
(-3410 5025);
DISPLAY 0.638298 (-3410 5025);
FORCEPROP 1 LAST PACK_TYPE 0402LF
J 0
(-3410 4975);
DISPLAY 0.638298 (-3410 4975);
FORCEPROP 1 LAST VALUE 4.7K
J 0
(-3405 5175);
DISPLAY 0.638298 (-3405 5175);
FORCEPROP 2 LAST CDS_LIB pure_quanta
J 0
(-3450 5100);
PAINT MONO (-3450 5100);
DISPLAY INVISIBLE (-3450 5100);
FORCEPROP 1 LAST PATH I19
J 0
(-3400 5275);
DISPLAY 0.978723 (-3400 5275);
PAINT WHITE (-3400 5275);
DISPLAY INVISIBLE (-3400 5275);
FORCEPROP 1 LAST PART_NUMBER CS24702JB10
J 0
(-3410 4925);
DISPLAY 0.638298 (-3410 4925);
DISPLAY INVISIBLE (-3410 4925);
FORCEADD UNIVERSAL_POWER..1
(-3450 5400);
FORCEPROP 3 LASTPIN (-3450 5350) SIG_NAME P3V3_AUX\g
J 0
(-3440 5360);
DISPLAY 0.659574 (-3440 5360);
PAINT MONO (-3440 5360);
DISPLAY INVISIBLE (-3440 5360);
FORCEPROP 1 LAST HDL_POWER P3V3_AUX
J 1
(-3450 5450);
DISPLAY 0.872340 (-3450 5450);
PAINT GREEN (-3450 5450);
FORCEPROP 2 LAST CDS_LIB pure_quanta_power
J 0
(-3450 5400);
PAINT MONO (-3450 5400);
DISPLAY INVISIBLE (-3450 5400);
FORCEPROP 1 LAST PATH I21
J 0
(-3400 5425);
DISPLAY 0.872340 (-3400 5425);
PAINT AQUA (-3400 5425);
DISPLAY INVISIBLE (-3400 5425);
FORCEADD OFFPAGE..4
R 2
(-425 7475);
FORCEPROP 2 LAST $XR0 116 
J 0
(-677 7475);
DISPLAY 0.638298 (-677 7475);
PAINT MONO (-677 7475);
FORCEPROP 2 LAST CDS_LIB standard
J 0
(-425 7475);
DISPLAY INVISIBLE (-425 7475);
FORCEPROP 1 LAST OFFPAGE TRUE
J 2
(-750 7350);
DISPLAY 0.872340 (-750 7350);
PAINT GREEN (-750 7350);
DISPLAY INVISIBLE (-750 7350);
FORCEPROP 1 LAST COMMENT_BODY TRUE
J 2
(-400 7375);
DISPLAY 0.872340 (-400 7375);
PAINT GREEN (-400 7375);
DISPLAY INVISIBLE (-400 7375);
FORCEPROP 2 LAST PATH I22
J 0
(-600 7525);
DISPLAY 1.021277 (-600 7525);
DISPLAY INVISIBLE (-600 7525);
FORCEADD UNIVERSAL_GND..1
(1100 7150);
FORCEPROP 3 LASTPIN (1100 7200) SIG_NAME GND\g
J 0
(1110 7210);
DISPLAY 0.659574 (1110 7210);
PAINT MONO (1110 7210);
DISPLAY INVISIBLE (1110 7210);
FORCEPROP 2 LAST CDS_LIB pure_quanta_power
J 0
(1100 7150);
DISPLAY INVISIBLE (1100 7150);
FORCEPROP 1 LAST HDL_POWER GND
J 1
(1125 7075);
DISPLAY 0.872340 (1125 7075);
PAINT GREEN (1125 7075);
DISPLAY INVISIBLE (1125 7075);
FORCEPROP 1 LAST PATH I23
J 0
(1175 7150);
DISPLAY 0.872340 (1175 7150);
PAINT AQUA (1175 7150);
DISPLAY INVISIBLE (1175 7150);
FORCEADD Q_RES..2
(1100 7925);
FORCEPROP 1 LAST LOCATION R2841
J 0
(1145 8050);
DISPLAY 0.638298 (1145 8050);
FORCEPROP 2 LAST $SEC 1
J 0
(1150 8150);
DISPLAY 0.680851 (1150 8150);
PAINT MONO (1150 8150);
DISPLAY INVISIBLE (1150 8150);
FORCEPROP 2 LAST CDS_SEC 1
J 0
(1150 8150);
DISPLAY 1.021277 (1150 8150);
DISPLAY INVISIBLE (1150 8150);
FORCEPROP 1 LASTPIN (1100 8025) $PN 1
J 0
(1105 7987);
DISPLAY 0.787234 (1105 7987);
FORCEPROP 1 LASTPIN (1100 7825) $PN 2
J 0
(1105 7835);
DISPLAY 0.787234 (1105 7835);
FORCEPROP 1 LAST VALUE 4.7K
J 0
(1145 8000);
DISPLAY 0.638298 (1145 8000);
FORCEPROP 1 LAST TOLERANCE 5%
J 0
(1145 7950);
DISPLAY 0.638298 (1145 7950);
FORCEPROP 1 LAST MATERIAL CHIP
J 0
(1140 7850);
DISPLAY 0.638298 (1140 7850);
FORCEPROP 1 LAST WATTAGE 1/16W
J 0
(1140 7900);
DISPLAY 0.638298 (1140 7900);
FORCEPROP 1 LAST PACK_TYPE 0402LF
J 0
(1140 7800);
DISPLAY 0.638298 (1140 7800);
FORCEPROP 2 LAST CDS_LIB pure_quanta
J 0
(1100 7925);
PAINT MONO (1100 7925);
DISPLAY INVISIBLE (1100 7925);
FORCEPROP 1 LAST PATH I24
J 0
(1150 8100);
DISPLAY 0.978723 (1150 8100);
PAINT WHITE (1150 8100);
DISPLAY INVISIBLE (1150 8100);
FORCEPROP 1 LAST PART_NUMBER CS24702JB10
J 0
(1140 7750);
DISPLAY 0.638298 (1140 7750);
DISPLAY INVISIBLE (1140 7750);
FORCEADD UNIVERSAL_POWER..1
(1100 8225);
FORCEPROP 3 LASTPIN (1100 8175) SIG_NAME P3V3_AUX\g
J 0
(1110 8185);
DISPLAY 0.659574 (1110 8185);
PAINT MONO (1110 8185);
DISPLAY INVISIBLE (1110 8185);
FORCEPROP 1 LAST HDL_POWER P3V3_AUX
J 1
(1100 8275);
DISPLAY 0.872340 (1100 8275);
PAINT GREEN (1100 8275);
FORCEPROP 2 LAST CDS_LIB pure_quanta_power
J 0
(1100 8225);
PAINT MONO (1100 8225);
DISPLAY INVISIBLE (1100 8225);
FORCEPROP 1 LAST PATH I25
J 0
(1150 8250);
DISPLAY 0.872340 (1150 8250);
PAINT AQUA (1150 8250);
DISPLAY INVISIBLE (1150 8250);
FORCEADD OFFPAGE..4
R 2
(-425 6100);
FORCEPROP 2 LAST $XR0 121 
J 0
(-677 6100);
DISPLAY 0.638298 (-677 6100);
PAINT MONO (-677 6100);
FORCEPROP 2 LAST CDS_LIB standard
J 0
(-425 6100);
DISPLAY INVISIBLE (-425 6100);
FORCEPROP 1 LAST OFFPAGE TRUE
J 2
(-750 5975);
DISPLAY 0.872340 (-750 5975);
PAINT GREEN (-750 5975);
DISPLAY INVISIBLE (-750 5975);
FORCEPROP 1 LAST COMMENT_BODY TRUE
J 2
(-400 6000);
DISPLAY 0.872340 (-400 6000);
PAINT GREEN (-400 6000);
DISPLAY INVISIBLE (-400 6000);
FORCEPROP 2 LAST PATH I28
J 0
(-600 6150);
DISPLAY 1.021277 (-600 6150);
DISPLAY INVISIBLE (-600 6150);
FORCEADD UNIVERSAL_GND..1
(1100 5775);
FORCEPROP 3 LASTPIN (1100 5825) SIG_NAME GND\g
J 0
(1110 5835);
DISPLAY 0.659574 (1110 5835);
PAINT MONO (1110 5835);
DISPLAY INVISIBLE (1110 5835);
FORCEPROP 2 LAST CDS_LIB pure_quanta_power
J 0
(1100 5775);
DISPLAY INVISIBLE (1100 5775);
FORCEPROP 1 LAST HDL_POWER GND
J 1
(1125 5700);
DISPLAY 0.872340 (1125 5700);
PAINT GREEN (1125 5700);
DISPLAY INVISIBLE (1125 5700);
FORCEPROP 1 LAST PATH I29
J 0
(1175 5775);
DISPLAY 0.872340 (1175 5775);
PAINT AQUA (1175 5775);
DISPLAY INVISIBLE (1175 5775);
FORCEADD Q_RES..2
(1100 6625);
FORCEPROP 1 LAST LOCATION R2842
J 0
(1145 6750);
DISPLAY 0.638298 (1145 6750);
FORCEPROP 2 LAST $SEC 1
J 0
(1150 6850);
DISPLAY 0.680851 (1150 6850);
PAINT MONO (1150 6850);
DISPLAY INVISIBLE (1150 6850);
FORCEPROP 2 LAST CDS_SEC 1
J 0
(1150 6850);
DISPLAY 1.021277 (1150 6850);
DISPLAY INVISIBLE (1150 6850);
FORCEPROP 1 LASTPIN (1100 6725) $PN 1
J 0
(1105 6687);
DISPLAY 0.787234 (1105 6687);
FORCEPROP 1 LASTPIN (1100 6525) $PN 2
J 0
(1105 6535);
DISPLAY 0.787234 (1105 6535);
FORCEPROP 1 LAST VALUE 4.7K
J 0
(1145 6700);
DISPLAY 0.638298 (1145 6700);
FORCEPROP 1 LAST TOLERANCE 5%
J 0
(1145 6650);
DISPLAY 0.638298 (1145 6650);
FORCEPROP 1 LAST PACK_TYPE 0402LF
J 0
(1140 6500);
DISPLAY 0.638298 (1140 6500);
FORCEPROP 1 LAST MATERIAL CHIP
J 0
(1140 6550);
DISPLAY 0.638298 (1140 6550);
FORCEPROP 1 LAST WATTAGE 1/16W
J 0
(1140 6600);
DISPLAY 0.638298 (1140 6600);
FORCEPROP 2 LAST CDS_LIB pure_quanta
J 0
(1100 6625);
PAINT MONO (1100 6625);
DISPLAY INVISIBLE (1100 6625);
FORCEPROP 1 LAST PATH I30
J 0
(1150 6800);
DISPLAY 0.978723 (1150 6800);
PAINT WHITE (1150 6800);
DISPLAY INVISIBLE (1150 6800);
FORCEPROP 1 LAST PART_NUMBER CS24702JB10
J 0
(1140 6450);
DISPLAY 0.638298 (1140 6450);
DISPLAY INVISIBLE (1140 6450);
FORCEADD UNIVERSAL_POWER..1
(1100 6925);
FORCEPROP 3 LASTPIN (1100 6875) SIG_NAME P3V3_AUX\g
J 0
(1110 6885);
DISPLAY 0.659574 (1110 6885);
PAINT MONO (1110 6885);
DISPLAY INVISIBLE (1110 6885);
FORCEPROP 1 LAST HDL_POWER P3V3_AUX
J 1
(1100 6975);
DISPLAY 0.872340 (1100 6975);
PAINT GREEN (1100 6975);
FORCEPROP 2 LAST CDS_LIB pure_quanta_power
J 0
(1100 6925);
PAINT MONO (1100 6925);
DISPLAY INVISIBLE (1100 6925);
FORCEPROP 1 LAST PATH I31
J 0
(1150 6950);
DISPLAY 0.872340 (1150 6950);
PAINT AQUA (1150 6950);
DISPLAY INVISIBLE (1150 6950);
FORCEADD MOSFET_NCH_DUAL..1
(-3575 7400);
FORCEPROP 1 LAST LOCATION Q67
J 0
(-3424 7374);
DISPLAY 0.723404 (-3424 7374);
PAINT GREEN (-3424 7374);
FORCEPROP 0 LAST $SEC 1
J 0
(-3400 7525);
DISPLAY 0.680851 (-3400 7525);
PAINT MONO (-3400 7525);
DISPLAY INVISIBLE (-3400 7525);
FORCEPROP 2 LAST CDS_SEC 1
J 0
(-3400 7525);
DISPLAY 1.021277 (-3400 7525);
DISPLAY INVISIBLE (-3400 7525);
FORCEPROP 0 LASTPIN (-3525 7600) $PN 6
R 1
J 0
(-3535 7610);
DISPLAY 0.680851 (-3535 7610);
PAINT MONO (-3535 7610);
FORCEPROP 0 LASTPIN (-3775 7350) $PN 2
J 2
(-3785 7360);
DISPLAY 0.680851 (-3785 7360);
PAINT MONO (-3785 7360);
FORCEPROP 0 LASTPIN (-3525 7200) $PN 1
R 1
J 2
(-3535 7190);
DISPLAY 0.680851 (-3535 7190);
PAINT MONO (-3535 7190);
FORCEPROP 2 LAST PART_TYPE SMLF
J 0
(-3400 7475);
DISPLAY 1.021277 (-3400 7475);
FORCEPROP 1 LAST MATERIAL IC
J 0
(-3424 7249);
DISPLAY 0.723404 (-3424 7249);
PAINT GREEN (-3424 7249);
FORCEPROP 2 LAST VALUE PJT138K
J 0
(-3400 7425);
DISPLAY 1.021277 (-3400 7425);
FORCEPROP 2 LAST CDS_LIB pure_quanta
J 0
(-3575 7400);
DISPLAY INVISIBLE (-3575 7400);
FORCEPROP 1 LAST NEEDS_NO_SIZE TRUE
J 0
(-3575 7399);
DISPLAY 0.468085 (-3575 7399);
PAINT GREEN (-3575 7399);
DISPLAY INVISIBLE (-3575 7399);
FORCEPROP 1 LAST CDS_LMAN_SYM_OUTLINE -150,150,150,-150
J 0
(-3575 7400);
DISPLAY 0.468085 (-3575 7400);
PAINT GREEN (-3575 7400);
DISPLAY INVISIBLE (-3575 7400);
FORCEPROP 1 LAST PATH I33
J 0
(-3575 7400);
DISPLAY 0.723404 (-3575 7400);
PAINT GREEN (-3575 7400);
DISPLAY INVISIBLE (-3575 7400);
FORCEPROP 1 LAST PART_NUMBER BAM138K0003
J 0
(-3424 7314);
DISPLAY 0.723404 (-3424 7314);
PAINT GREEN (-3424 7314);
DISPLAY INVISIBLE (-3424 7314);
FORCEADD MOSFET_NCH_DUAL..1
(-3500 4650);
FORCEPROP 1 LAST LOCATION Q70
J 0
(-3349 4624);
DISPLAY 0.723404 (-3349 4624);
PAINT GREEN (-3349 4624);
FORCEPROP 0 LAST $SEC 1
J 0
(-3325 4775);
DISPLAY 0.680851 (-3325 4775);
PAINT MONO (-3325 4775);
DISPLAY INVISIBLE (-3325 4775);
FORCEPROP 2 LAST CDS_SEC 1
J 0
(-3325 4775);
DISPLAY 1.021277 (-3325 4775);
DISPLAY INVISIBLE (-3325 4775);
FORCEPROP 0 LASTPIN (-3450 4850) $PN 6
R 1
J 0
(-3460 4860);
DISPLAY 0.680851 (-3460 4860);
PAINT MONO (-3460 4860);
FORCEPROP 0 LASTPIN (-3700 4600) $PN 2
J 2
(-3710 4610);
DISPLAY 0.680851 (-3710 4610);
PAINT MONO (-3710 4610);
FORCEPROP 0 LASTPIN (-3450 4450) $PN 1
R 1
J 2
(-3460 4440);
DISPLAY 0.680851 (-3460 4440);
PAINT MONO (-3460 4440);
FORCEPROP 1 LAST MATERIAL IC
J 0
(-3349 4499);
DISPLAY 0.723404 (-3349 4499);
PAINT GREEN (-3349 4499);
FORCEPROP 2 LAST VALUE PJT138K
J 0
(-3325 4675);
DISPLAY 1.021277 (-3325 4675);
FORCEPROP 2 LAST PART_TYPE SMLF
J 0
(-3325 4725);
DISPLAY 1.021277 (-3325 4725);
FORCEPROP 1 LAST CDS_LMAN_SYM_OUTLINE -150,150,150,-150
J 0
(-3500 4650);
DISPLAY 0.468085 (-3500 4650);
PAINT GREEN (-3500 4650);
DISPLAY INVISIBLE (-3500 4650);
FORCEPROP 1 LAST NEEDS_NO_SIZE TRUE
J 0
(-3500 4649);
DISPLAY 0.468085 (-3500 4649);
PAINT GREEN (-3500 4649);
DISPLAY INVISIBLE (-3500 4649);
FORCEPROP 2 LAST CDS_LIB pure_quanta
J 0
(-3500 4650);
DISPLAY INVISIBLE (-3500 4650);
FORCEPROP 1 LAST PATH I35
J 0
(-3500 4650);
DISPLAY 0.723404 (-3500 4650);
PAINT GREEN (-3500 4650);
DISPLAY INVISIBLE (-3500 4650);
FORCEPROP 1 LAST PART_NUMBER BAM138K0003
J 0
(-3349 4564);
DISPLAY 0.723404 (-3349 4564);
PAINT GREEN (-3349 4564);
DISPLAY INVISIBLE (-3349 4564);
FORCEADD MOSFET_NCH_DUAL..1
(1050 6150);
FORCEPROP 1 LAST LOCATION Q72
J 0
(1201 6124);
DISPLAY 0.723404 (1201 6124);
PAINT GREEN (1201 6124);
FORCEPROP 0 LAST $SEC 1
J 0
(1225 6275);
DISPLAY 0.680851 (1225 6275);
PAINT MONO (1225 6275);
DISPLAY INVISIBLE (1225 6275);
FORCEPROP 2 LAST CDS_SEC 1
J 0
(1225 6275);
DISPLAY 1.021277 (1225 6275);
DISPLAY INVISIBLE (1225 6275);
FORCEPROP 0 LASTPIN (1100 6350) $PN 6
R 1
J 0
(1090 6360);
DISPLAY 0.680851 (1090 6360);
PAINT MONO (1090 6360);
FORCEPROP 0 LASTPIN (850 6100) $PN 2
J 2
(840 6110);
DISPLAY 0.680851 (840 6110);
PAINT MONO (840 6110);
FORCEPROP 0 LASTPIN (1100 5950) $PN 1
R 1
J 2
(1090 5940);
DISPLAY 0.680851 (1090 5940);
PAINT MONO (1090 5940);
FORCEPROP 2 LAST PART_TYPE SMLF
J 0
(1225 6225);
DISPLAY 1.021277 (1225 6225);
FORCEPROP 2 LAST VALUE PJT138K
J 0
(1225 6175);
DISPLAY 1.021277 (1225 6175);
FORCEPROP 1 LAST MATERIAL IC
J 0
(1201 5999);
DISPLAY 0.723404 (1201 5999);
PAINT GREEN (1201 5999);
FORCEPROP 1 LAST CDS_LMAN_SYM_OUTLINE -150,150,150,-150
J 0
(1050 6150);
DISPLAY 0.468085 (1050 6150);
PAINT GREEN (1050 6150);
DISPLAY INVISIBLE (1050 6150);
FORCEPROP 1 LAST NEEDS_NO_SIZE TRUE
J 0
(1050 6149);
DISPLAY 0.468085 (1050 6149);
PAINT GREEN (1050 6149);
DISPLAY INVISIBLE (1050 6149);
FORCEPROP 2 LAST CDS_LIB pure_quanta
J 0
(1050 6150);
DISPLAY INVISIBLE (1050 6150);
FORCEPROP 1 LAST PATH I37
J 0
(1050 6150);
DISPLAY 0.723404 (1050 6150);
PAINT GREEN (1050 6150);
DISPLAY INVISIBLE (1050 6150);
FORCEPROP 1 LAST PART_NUMBER BAM138K0003
J 0
(1201 6064);
DISPLAY 0.723404 (1201 6064);
PAINT GREEN (1201 6064);
DISPLAY INVISIBLE (1201 6064);
FORCEADD UNIVERSAL_POWER..1
(-4700 7875);
FORCEPROP 3 LASTPIN (-4700 7825) SIG_NAME P3V3_AUX\g
J 0
(-4690 7835);
DISPLAY 0.659574 (-4690 7835);
PAINT MONO (-4690 7835);
DISPLAY INVISIBLE (-4690 7835);
FORCEPROP 1 LAST HDL_POWER P3V3_AUX
J 1
(-4700 7925);
DISPLAY 0.872340 (-4700 7925);
PAINT GREEN (-4700 7925);
FORCEPROP 2 LAST CDS_LIB pure_quanta_power
J 0
(-4700 7875);
PAINT MONO (-4700 7875);
DISPLAY INVISIBLE (-4700 7875);
FORCEPROP 1 LAST PATH I46
J 0
(-4650 7900);
DISPLAY 0.872340 (-4650 7900);
PAINT AQUA (-4650 7900);
DISPLAY INVISIBLE (-4650 7900);
FORCEADD UNIVERSAL_POWER..1
(-4675 6475);
FORCEPROP 3 LASTPIN (-4675 6425) SIG_NAME P3V3_AUX\g
J 0
(-4665 6435);
DISPLAY 0.659574 (-4665 6435);
PAINT MONO (-4665 6435);
DISPLAY INVISIBLE (-4665 6435);
FORCEPROP 1 LAST HDL_POWER P3V3_AUX
J 1
(-4675 6525);
DISPLAY 0.872340 (-4675 6525);
PAINT GREEN (-4675 6525);
FORCEPROP 2 LAST CDS_LIB pure_quanta_power
J 0
(-4675 6475);
PAINT MONO (-4675 6475);
DISPLAY INVISIBLE (-4675 6475);
FORCEPROP 1 LAST PATH I47
J 0
(-4625 6500);
DISPLAY 0.872340 (-4625 6500);
PAINT AQUA (-4625 6500);
DISPLAY INVISIBLE (-4625 6500);
FORCEADD UNIVERSAL_POWER..1
(-4625 5125);
FORCEPROP 3 LASTPIN (-4625 5075) SIG_NAME P3V3_AUX\g
J 0
(-4615 5085);
DISPLAY 0.659574 (-4615 5085);
PAINT MONO (-4615 5085);
DISPLAY INVISIBLE (-4615 5085);
FORCEPROP 1 LAST HDL_POWER P3V3_AUX
J 1
(-4625 5175);
DISPLAY 0.872340 (-4625 5175);
PAINT GREEN (-4625 5175);
FORCEPROP 2 LAST CDS_LIB pure_quanta_power
J 0
(-4625 5125);
PAINT MONO (-4625 5125);
DISPLAY INVISIBLE (-4625 5125);
FORCEPROP 1 LAST PATH I49
J 0
(-4575 5150);
DISPLAY 0.872340 (-4575 5150);
PAINT AQUA (-4575 5150);
DISPLAY INVISIBLE (-4575 5150);
FORCEADD UNIVERSAL_POWER..1
(-150 8000);
FORCEPROP 3 LASTPIN (-150 7950) SIG_NAME P3V3_AUX\g
J 0
(-140 7960);
DISPLAY 0.659574 (-140 7960);
PAINT MONO (-140 7960);
DISPLAY INVISIBLE (-140 7960);
FORCEPROP 1 LAST HDL_POWER P3V3_AUX
J 1
(-150 8050);
DISPLAY 0.872340 (-150 8050);
PAINT GREEN (-150 8050);
FORCEPROP 2 LAST CDS_LIB pure_quanta_power
J 0
(-150 8000);
PAINT MONO (-150 8000);
DISPLAY INVISIBLE (-150 8000);
FORCEPROP 1 LAST PATH I51
J 0
(-100 8025);
DISPLAY 0.872340 (-100 8025);
PAINT AQUA (-100 8025);
DISPLAY INVISIBLE (-100 8025);
FORCEADD UNIVERSAL_POWER..1
(-150 6625);
FORCEPROP 3 LASTPIN (-150 6575) SIG_NAME P3V3_AUX\g
J 0
(-140 6585);
DISPLAY 0.659574 (-140 6585);
PAINT MONO (-140 6585);
DISPLAY INVISIBLE (-140 6585);
FORCEPROP 1 LAST HDL_POWER P3V3_AUX
J 1
(-150 6675);
DISPLAY 0.872340 (-150 6675);
PAINT GREEN (-150 6675);
FORCEPROP 2 LAST CDS_LIB pure_quanta_power
J 0
(-150 6625);
PAINT MONO (-150 6625);
DISPLAY INVISIBLE (-150 6625);
FORCEPROP 1 LAST PATH I53
J 0
(-100 6650);
DISPLAY 0.872340 (-100 6650);
PAINT AQUA (-100 6650);
DISPLAY INVISIBLE (-100 6650);
FORCEADD UNIVERSAL_GND..1
(-4675 6950);
FORCEPROP 3 LASTPIN (-4675 7000) SIG_NAME GND\g
J 0
(-4665 7010);
DISPLAY 0.659574 (-4665 7010);
PAINT MONO (-4665 7010);
DISPLAY INVISIBLE (-4665 7010);
FORCEPROP 2 LAST CDS_LIB pure_quanta_power
J 0
(-4675 6950);
DISPLAY INVISIBLE (-4675 6950);
FORCEPROP 1 LAST HDL_POWER GND
J 1
(-4650 6875);
DISPLAY 0.872340 (-4650 6875);
PAINT GREEN (-4650 6875);
DISPLAY INVISIBLE (-4650 6875);
FORCEPROP 1 LAST PATH I55
J 0
(-4600 6950);
DISPLAY 0.872340 (-4600 6950);
PAINT AQUA (-4600 6950);
DISPLAY INVISIBLE (-4600 6950);
FORCEADD Q_RES..2
(-4675 7150);
FORCEPROP 1 LAST LOCATION R2831
J 0
(-4630 7275);
DISPLAY 0.978723 (-4630 7275);
FORCEPROP 0 LAST $SEC 1
J 0
(-4625 7325);
DISPLAY 0.680851 (-4625 7325);
PAINT MONO (-4625 7325);
DISPLAY INVISIBLE (-4625 7325);
FORCEPROP 0 LAST CDS_SEC 1
J 0
(-4625 7325);
DISPLAY 1.021277 (-4625 7325);
DISPLAY INVISIBLE (-4625 7325);
FORCEPROP 1 LASTPIN (-4675 7250) $PN 1
J 0
(-4670 7212);
DISPLAY 0.787234 (-4670 7212);
PAINT MONO (-4670 7212);
FORCEPROP 1 LASTPIN (-4675 7050) $PN 2
J 0
(-4670 7060);
DISPLAY 0.787234 (-4670 7060);
PAINT MONO (-4670 7060);
FORCEPROP 1 LAST PACK_TYPE 0402LF
J 0
(-4635 6975);
DISPLAY 0.510638 (-4635 6975);
FORCEPROP 1 LAST WATTAGE 1/16W
J 0
(-4635 7125);
DISPLAY 0.510638 (-4635 7125);
FORCEPROP 1 LAST MATERIAL EMPTY
J 0
(-4635 7075);
DISPLAY 0.510638 (-4635 7075);
PAINT RED (-4635 7075);
FORCEPROP 1 LAST TOLERANCE 1%
J 0
(-4630 7175);
DISPLAY 0.510638 (-4630 7175);
FORCEPROP 1 LAST VALUE 100K
J 0
(-4630 7225);
DISPLAY 0.510638 (-4630 7225);
FORCEPROP 2 LAST CDS_LIB pure_quanta
J 0
(-4675 7150);
DISPLAY INVISIBLE (-4675 7150);
FORCEPROP 1 LAST PATH I56
J 0
(-4625 7325);
DISPLAY 0.978723 (-4625 7325);
PAINT WHITE (-4625 7325);
DISPLAY INVISIBLE (-4625 7325);
FORCEPROP 1 LAST PART_NUMBER CS41002FB09
J 0
(-4635 7025);
DISPLAY 0.510638 (-4635 7025);
DISPLAY INVISIBLE (-4635 7025);
FORCEADD UNIVERSAL_GND..1
(-4650 5575);
FORCEPROP 3 LASTPIN (-4650 5625) SIG_NAME GND\g
J 0
(-4640 5635);
DISPLAY 0.659574 (-4640 5635);
PAINT MONO (-4640 5635);
DISPLAY INVISIBLE (-4640 5635);
FORCEPROP 2 LAST CDS_LIB pure_quanta_power
J 0
(-4650 5575);
DISPLAY INVISIBLE (-4650 5575);
FORCEPROP 1 LAST HDL_POWER GND
J 1
(-4625 5500);
DISPLAY 0.872340 (-4625 5500);
PAINT GREEN (-4625 5500);
DISPLAY INVISIBLE (-4625 5500);
FORCEPROP 1 LAST PATH I57
J 0
(-4575 5575);
DISPLAY 0.872340 (-4575 5575);
PAINT AQUA (-4575 5575);
DISPLAY INVISIBLE (-4575 5575);
FORCEADD Q_RES..2
(-4650 5750);
FORCEPROP 1 LAST LOCATION R2829
J 0
(-4605 5875);
DISPLAY 0.978723 (-4605 5875);
FORCEPROP 0 LAST $SEC 1
J 0
(-4600 5925);
DISPLAY 0.680851 (-4600 5925);
PAINT MONO (-4600 5925);
DISPLAY INVISIBLE (-4600 5925);
FORCEPROP 0 LAST CDS_SEC 1
J 0
(-4600 5925);
DISPLAY 1.021277 (-4600 5925);
DISPLAY INVISIBLE (-4600 5925);
FORCEPROP 1 LASTPIN (-4650 5850) $PN 1
J 0
(-4645 5812);
DISPLAY 0.787234 (-4645 5812);
PAINT MONO (-4645 5812);
FORCEPROP 1 LASTPIN (-4650 5650) $PN 2
J 0
(-4645 5660);
DISPLAY 0.787234 (-4645 5660);
PAINT MONO (-4645 5660);
FORCEPROP 1 LAST VALUE 100K
J 0
(-4605 5825);
DISPLAY 0.510638 (-4605 5825);
FORCEPROP 1 LAST TOLERANCE 1%
J 0
(-4605 5775);
DISPLAY 0.510638 (-4605 5775);
FORCEPROP 1 LAST PACK_TYPE 0402LF
J 0
(-4610 5575);
DISPLAY 0.510638 (-4610 5575);
FORCEPROP 1 LAST MATERIAL EMPTY
J 0
(-4610 5675);
DISPLAY 0.510638 (-4610 5675);
PAINT RED (-4610 5675);
FORCEPROP 1 LAST WATTAGE 1/16W
J 0
(-4610 5725);
DISPLAY 0.510638 (-4610 5725);
FORCEPROP 2 LAST CDS_LIB pure_quanta
J 0
(-4650 5750);
DISPLAY INVISIBLE (-4650 5750);
FORCEPROP 1 LAST PATH I58
J 0
(-4600 5925);
DISPLAY 0.978723 (-4600 5925);
PAINT WHITE (-4600 5925);
DISPLAY INVISIBLE (-4600 5925);
FORCEPROP 1 LAST PART_NUMBER CS41002FB09
J 0
(-4610 5625);
DISPLAY 0.510638 (-4610 5625);
DISPLAY INVISIBLE (-4610 5625);
FORCEADD UNIVERSAL_GND..1
(-4600 4225);
FORCEPROP 3 LASTPIN (-4600 4275) SIG_NAME GND\g
J 0
(-4590 4285);
DISPLAY 0.659574 (-4590 4285);
PAINT MONO (-4590 4285);
DISPLAY INVISIBLE (-4590 4285);
FORCEPROP 2 LAST CDS_LIB pure_quanta_power
J 0
(-4600 4225);
DISPLAY INVISIBLE (-4600 4225);
FORCEPROP 1 LAST HDL_POWER GND
J 1
(-4575 4150);
DISPLAY 0.872340 (-4575 4150);
PAINT GREEN (-4575 4150);
DISPLAY INVISIBLE (-4575 4150);
FORCEPROP 1 LAST PATH I59
J 0
(-4525 4225);
DISPLAY 0.872340 (-4525 4225);
PAINT AQUA (-4525 4225);
DISPLAY INVISIBLE (-4525 4225);
FORCEADD OFFPAGE..4
R 2
(-4950 7350);
FORCEPROP 2 LAST $XR0 119 
J 0
(-5232 7350);
DISPLAY 0.638298 (-5232 7350);
PAINT MONO (-5232 7350);
FORCEPROP 2 LAST CDS_LIB standard
J 0
(-4950 7350);
DISPLAY INVISIBLE (-4950 7350);
FORCEPROP 1 LAST OFFPAGE TRUE
J 2
(-5275 7225);
DISPLAY 0.872340 (-5275 7225);
PAINT GREEN (-5275 7225);
DISPLAY INVISIBLE (-5275 7225);
FORCEPROP 1 LAST COMMENT_BODY TRUE
J 2
(-4925 7250);
DISPLAY 0.872340 (-4925 7250);
PAINT GREEN (-4925 7250);
DISPLAY INVISIBLE (-4925 7250);
FORCEPROP 2 LAST PATH I6
J 0
(-5125 7400);
DISPLAY 1.021277 (-5125 7400);
DISPLAY INVISIBLE (-5125 7400);
FORCEADD Q_RES..2
(-4600 4400);
FORCEPROP 1 LAST LOCATION R2833
J 0
(-4555 4525);
DISPLAY 0.978723 (-4555 4525);
FORCEPROP 0 LAST $SEC 1
J 0
(-4550 4575);
DISPLAY 0.680851 (-4550 4575);
PAINT MONO (-4550 4575);
DISPLAY INVISIBLE (-4550 4575);
FORCEPROP 0 LAST CDS_SEC 1
J 0
(-4550 4575);
DISPLAY 1.021277 (-4550 4575);
DISPLAY INVISIBLE (-4550 4575);
FORCEPROP 1 LASTPIN (-4600 4500) $PN 1
J 0
(-4595 4462);
DISPLAY 0.787234 (-4595 4462);
PAINT MONO (-4595 4462);
FORCEPROP 1 LASTPIN (-4600 4300) $PN 2
J 0
(-4595 4310);
DISPLAY 0.787234 (-4595 4310);
PAINT MONO (-4595 4310);
FORCEPROP 1 LAST VALUE 100K
J 0
(-4555 4475);
DISPLAY 0.510638 (-4555 4475);
FORCEPROP 1 LAST TOLERANCE 1%
J 0
(-4555 4425);
DISPLAY 0.510638 (-4555 4425);
FORCEPROP 1 LAST WATTAGE 1/16W
J 0
(-4560 4375);
DISPLAY 0.510638 (-4560 4375);
FORCEPROP 1 LAST MATERIAL EMPTY
J 0
(-4560 4325);
DISPLAY 0.510638 (-4560 4325);
PAINT RED (-4560 4325);
FORCEPROP 1 LAST PACK_TYPE 0402LF
J 0
(-4560 4225);
DISPLAY 0.510638 (-4560 4225);
FORCEPROP 2 LAST CDS_LIB pure_quanta
J 0
(-4600 4400);
DISPLAY INVISIBLE (-4600 4400);
FORCEPROP 1 LAST PATH I60
J 0
(-4550 4575);
DISPLAY 0.978723 (-4550 4575);
PAINT WHITE (-4550 4575);
DISPLAY INVISIBLE (-4550 4575);
FORCEPROP 1 LAST PART_NUMBER CS41002FB09
J 0
(-4560 4275);
DISPLAY 0.510638 (-4560 4275);
DISPLAY INVISIBLE (-4560 4275);
FORCEADD UNIVERSAL_GND..1
(-125 7100);
FORCEPROP 3 LASTPIN (-125 7150) SIG_NAME GND\g
J 0
(-115 7160);
DISPLAY 0.659574 (-115 7160);
PAINT MONO (-115 7160);
DISPLAY INVISIBLE (-115 7160);
FORCEPROP 2 LAST CDS_LIB pure_quanta_power
J 0
(-125 7100);
DISPLAY INVISIBLE (-125 7100);
FORCEPROP 1 LAST HDL_POWER GND
J 1
(-100 7025);
DISPLAY 0.872340 (-100 7025);
PAINT GREEN (-100 7025);
DISPLAY INVISIBLE (-100 7025);
FORCEPROP 1 LAST PATH I61
J 0
(-50 7100);
DISPLAY 0.872340 (-50 7100);
PAINT AQUA (-50 7100);
DISPLAY INVISIBLE (-50 7100);
FORCEADD Q_RES..2
(-125 7275);
FORCEPROP 1 LAST LOCATION R2838
J 0
(-80 7400);
DISPLAY 0.978723 (-80 7400);
FORCEPROP 0 LAST $SEC 1
J 0
(-75 7450);
DISPLAY 0.680851 (-75 7450);
PAINT MONO (-75 7450);
DISPLAY INVISIBLE (-75 7450);
FORCEPROP 0 LAST CDS_SEC 1
J 0
(-75 7450);
DISPLAY 1.021277 (-75 7450);
DISPLAY INVISIBLE (-75 7450);
FORCEPROP 1 LASTPIN (-125 7375) $PN 1
J 0
(-120 7337);
DISPLAY 0.787234 (-120 7337);
PAINT MONO (-120 7337);
FORCEPROP 1 LASTPIN (-125 7175) $PN 2
J 0
(-120 7185);
DISPLAY 0.787234 (-120 7185);
PAINT MONO (-120 7185);
FORCEPROP 1 LAST VALUE 100K
J 0
(-80 7350);
DISPLAY 0.510638 (-80 7350);
FORCEPROP 1 LAST TOLERANCE 1%
J 0
(-80 7300);
DISPLAY 0.510638 (-80 7300);
FORCEPROP 1 LAST WATTAGE 1/16W
J 0
(-85 7250);
DISPLAY 0.510638 (-85 7250);
FORCEPROP 1 LAST MATERIAL CHIP
J 0
(-85 7200);
DISPLAY 0.510638 (-85 7200);
FORCEPROP 1 LAST PACK_TYPE 0402LF
J 0
(-85 7100);
DISPLAY 0.510638 (-85 7100);
FORCEPROP 2 LAST CDS_LIB pure_quanta
J 0
(-125 7275);
DISPLAY INVISIBLE (-125 7275);
FORCEPROP 1 LAST PATH I62
J 0
(-75 7450);
DISPLAY 0.978723 (-75 7450);
PAINT WHITE (-75 7450);
DISPLAY INVISIBLE (-75 7450);
FORCEPROP 1 LAST PART_NUMBER CS41002FB09
J 0
(-85 7150);
DISPLAY 0.510638 (-85 7150);
DISPLAY INVISIBLE (-85 7150);
FORCEADD UNIVERSAL_GND..1
(-125 5700);
FORCEPROP 3 LASTPIN (-125 5750) SIG_NAME GND\g
J 0
(-115 5760);
DISPLAY 0.659574 (-115 5760);
PAINT MONO (-115 5760);
DISPLAY INVISIBLE (-115 5760);
FORCEPROP 2 LAST CDS_LIB pure_quanta_power
J 0
(-125 5700);
DISPLAY INVISIBLE (-125 5700);
FORCEPROP 1 LAST HDL_POWER GND
J 1
(-100 5625);
DISPLAY 0.872340 (-100 5625);
PAINT GREEN (-100 5625);
DISPLAY INVISIBLE (-100 5625);
FORCEPROP 1 LAST PATH I63
J 0
(-50 5700);
DISPLAY 0.872340 (-50 5700);
PAINT AQUA (-50 5700);
DISPLAY INVISIBLE (-50 5700);
FORCEADD Q_RES..2
(-4675 6225);
FORCEPROP 1 LAST LOCATION R2828
J 0
(-4630 6350);
DISPLAY 0.978723 (-4630 6350);
FORCEPROP 0 LAST $SEC 1
J 0
(-4625 6400);
DISPLAY 0.680851 (-4625 6400);
PAINT MONO (-4625 6400);
DISPLAY INVISIBLE (-4625 6400);
FORCEPROP 0 LAST CDS_SEC 1
J 0
(-4625 6400);
DISPLAY 1.021277 (-4625 6400);
DISPLAY INVISIBLE (-4625 6400);
FORCEPROP 1 LASTPIN (-4675 6325) $PN 1
J 0
(-4670 6287);
DISPLAY 0.787234 (-4670 6287);
PAINT MONO (-4670 6287);
FORCEPROP 1 LASTPIN (-4675 6125) $PN 2
J 0
(-4670 6135);
DISPLAY 0.787234 (-4670 6135);
PAINT MONO (-4670 6135);
FORCEPROP 1 LAST VALUE 100K
J 0
(-4630 6300);
DISPLAY 0.510638 (-4630 6300);
FORCEPROP 1 LAST MATERIAL CHIP
J 0
(-4635 6150);
DISPLAY 0.510638 (-4635 6150);
FORCEPROP 1 LAST TOLERANCE 1%
J 0
(-4630 6250);
DISPLAY 0.510638 (-4630 6250);
FORCEPROP 1 LAST WATTAGE 1/16W
J 0
(-4635 6200);
DISPLAY 0.510638 (-4635 6200);
FORCEPROP 1 LAST PACK_TYPE 0402LF
J 0
(-4635 6050);
DISPLAY 0.510638 (-4635 6050);
FORCEPROP 2 LAST CDS_LIB pure_quanta
J 0
(-4675 6225);
DISPLAY INVISIBLE (-4675 6225);
FORCEPROP 1 LAST PATH I66
J 0
(-4625 6400);
DISPLAY 0.978723 (-4625 6400);
PAINT WHITE (-4625 6400);
DISPLAY INVISIBLE (-4625 6400);
FORCEPROP 1 LAST PART_NUMBER CS41002FB09
J 0
(-4635 6100);
DISPLAY 0.510638 (-4635 6100);
DISPLAY INVISIBLE (-4635 6100);
FORCEADD Q_RES..2
(-4625 4875);
FORCEPROP 1 LAST LOCATION R2832
J 0
(-4580 5000);
DISPLAY 0.978723 (-4580 5000);
FORCEPROP 0 LAST $SEC 1
J 0
(-4575 5050);
DISPLAY 0.680851 (-4575 5050);
PAINT MONO (-4575 5050);
DISPLAY INVISIBLE (-4575 5050);
FORCEPROP 0 LAST CDS_SEC 1
J 0
(-4575 5050);
DISPLAY 1.021277 (-4575 5050);
DISPLAY INVISIBLE (-4575 5050);
FORCEPROP 1 LASTPIN (-4625 4975) $PN 1
J 0
(-4620 4937);
DISPLAY 0.787234 (-4620 4937);
PAINT MONO (-4620 4937);
FORCEPROP 1 LASTPIN (-4625 4775) $PN 2
J 0
(-4620 4785);
DISPLAY 0.787234 (-4620 4785);
PAINT MONO (-4620 4785);
FORCEPROP 1 LAST WATTAGE 1/16W
J 0
(-4585 4850);
DISPLAY 0.510638 (-4585 4850);
FORCEPROP 1 LAST TOLERANCE 1%
J 0
(-4580 4900);
DISPLAY 0.510638 (-4580 4900);
FORCEPROP 1 LAST VALUE 100K
J 0
(-4580 4950);
DISPLAY 0.510638 (-4580 4950);
FORCEPROP 1 LAST PACK_TYPE 0402LF
J 0
(-4585 4700);
DISPLAY 0.510638 (-4585 4700);
FORCEPROP 1 LAST MATERIAL CHIP
J 0
(-4585 4800);
DISPLAY 0.510638 (-4585 4800);
FORCEPROP 2 LAST CDS_LIB pure_quanta
J 0
(-4625 4875);
DISPLAY INVISIBLE (-4625 4875);
FORCEPROP 1 LAST PATH I67
J 0
(-4575 5050);
DISPLAY 0.978723 (-4575 5050);
PAINT WHITE (-4575 5050);
DISPLAY INVISIBLE (-4575 5050);
FORCEPROP 1 LAST PART_NUMBER CS41002FB09
J 0
(-4585 4750);
DISPLAY 0.510638 (-4585 4750);
DISPLAY INVISIBLE (-4585 4750);
FORCEADD Q_RES..2
(-4700 7625);
FORCEPROP 1 LAST LOCATION R2830
J 0
(-4655 7750);
DISPLAY 0.978723 (-4655 7750);
FORCEPROP 0 LAST $SEC 1
J 0
(-4650 7800);
DISPLAY 0.680851 (-4650 7800);
PAINT MONO (-4650 7800);
DISPLAY INVISIBLE (-4650 7800);
FORCEPROP 0 LAST CDS_SEC 1
J 0
(-4650 7800);
DISPLAY 1.021277 (-4650 7800);
DISPLAY INVISIBLE (-4650 7800);
FORCEPROP 1 LASTPIN (-4700 7725) $PN 1
J 0
(-4695 7687);
DISPLAY 0.787234 (-4695 7687);
PAINT MONO (-4695 7687);
FORCEPROP 1 LASTPIN (-4700 7525) $PN 2
J 0
(-4695 7535);
DISPLAY 0.787234 (-4695 7535);
PAINT MONO (-4695 7535);
FORCEPROP 1 LAST VALUE 100K
J 0
(-4655 7700);
DISPLAY 0.510638 (-4655 7700);
FORCEPROP 1 LAST TOLERANCE 1%
J 0
(-4655 7650);
DISPLAY 0.510638 (-4655 7650);
FORCEPROP 1 LAST WATTAGE 1/16W
J 0
(-4660 7600);
DISPLAY 0.510638 (-4660 7600);
FORCEPROP 1 LAST MATERIAL CHIP
J 0
(-4660 7550);
DISPLAY 0.510638 (-4660 7550);
FORCEPROP 1 LAST PACK_TYPE 0402LF
J 0
(-4660 7450);
DISPLAY 0.510638 (-4660 7450);
FORCEPROP 2 LAST CDS_LIB pure_quanta
J 0
(-4700 7625);
DISPLAY INVISIBLE (-4700 7625);
FORCEPROP 1 LAST PATH I68
J 0
(-4650 7800);
DISPLAY 0.978723 (-4650 7800);
PAINT WHITE (-4650 7800);
DISPLAY INVISIBLE (-4650 7800);
FORCEPROP 1 LAST PART_NUMBER CS41002FB09
J 0
(-4660 7500);
DISPLAY 0.510638 (-4660 7500);
DISPLAY INVISIBLE (-4660 7500);
FORCEADD OFFPAGE..4
R 2
(-4875 5950);
FORCEPROP 2 LAST $XR0 115 
J 0
(-5127 5950);
DISPLAY 0.638298 (-5127 5950);
PAINT MONO (-5127 5950);
FORCEPROP 2 LAST CDS_LIB standard
J 0
(-4875 5950);
DISPLAY INVISIBLE (-4875 5950);
FORCEPROP 1 LAST OFFPAGE TRUE
J 2
(-5200 5825);
DISPLAY 0.872340 (-5200 5825);
PAINT GREEN (-5200 5825);
DISPLAY INVISIBLE (-5200 5825);
FORCEPROP 1 LAST COMMENT_BODY TRUE
J 2
(-4850 5850);
DISPLAY 0.872340 (-4850 5850);
PAINT GREEN (-4850 5850);
DISPLAY INVISIBLE (-4850 5850);
FORCEPROP 2 LAST PATH I7
J 0
(-5050 6000);
DISPLAY 1.021277 (-5050 6000);
DISPLAY INVISIBLE (-5050 6000);
FORCEADD OFFPAGE..4
R 2
(-4875 4600);
FORCEPROP 2 LAST $XR0 115 
J 0
(-5127 4600);
DISPLAY 0.638298 (-5127 4600);
PAINT MONO (-5127 4600);
FORCEPROP 2 LAST CDS_LIB standard
J 0
(-4875 4600);
DISPLAY INVISIBLE (-4875 4600);
FORCEPROP 1 LAST OFFPAGE TRUE
J 2
(-5200 4475);
DISPLAY 0.872340 (-5200 4475);
PAINT GREEN (-5200 4475);
DISPLAY INVISIBLE (-5200 4475);
FORCEPROP 1 LAST COMMENT_BODY TRUE
J 2
(-4850 4500);
DISPLAY 0.872340 (-4850 4500);
PAINT GREEN (-4850 4500);
DISPLAY INVISIBLE (-4850 4500);
FORCEPROP 2 LAST PATH I8
J 0
(-5050 4650);
DISPLAY 1.021277 (-5050 4650);
DISPLAY INVISIBLE (-5050 4650);
FORCEADD Q_RES..2
(-150 7700);
FORCEPROP 1 LAST LOCATION R2837
J 0
(-105 7825);
DISPLAY 0.978723 (-105 7825);
FORCEPROP 0 LAST $SEC 1
J 0
(-100 7875);
DISPLAY 0.680851 (-100 7875);
PAINT MONO (-100 7875);
DISPLAY INVISIBLE (-100 7875);
FORCEPROP 0 LAST CDS_SEC 1
J 0
(-100 7875);
DISPLAY 1.021277 (-100 7875);
DISPLAY INVISIBLE (-100 7875);
FORCEPROP 1 LASTPIN (-150 7800) $PN 1
J 0
(-145 7762);
DISPLAY 0.787234 (-145 7762);
PAINT MONO (-145 7762);
FORCEPROP 1 LASTPIN (-150 7600) $PN 2
J 0
(-145 7610);
DISPLAY 0.787234 (-145 7610);
PAINT MONO (-145 7610);
FORCEPROP 1 LAST TOLERANCE 1%
J 0
(-105 7725);
DISPLAY 0.510638 (-105 7725);
FORCEPROP 1 LAST WATTAGE 1/16W
J 0
(-110 7675);
DISPLAY 0.510638 (-110 7675);
FORCEPROP 1 LAST MATERIAL EMPTY
J 0
(-125 7625);
DISPLAY 0.510638 (-125 7625);
PAINT RED (-125 7625);
FORCEPROP 1 LAST PACK_TYPE 0402LF
J 0
(-110 7525);
DISPLAY 0.510638 (-110 7525);
FORCEPROP 1 LAST VALUE 100K
J 0
(-105 7775);
DISPLAY 0.510638 (-105 7775);
FORCEPROP 2 LAST CDS_LIB pure_quanta
J 0
(-150 7700);
DISPLAY INVISIBLE (-150 7700);
FORCEPROP 1 LAST PATH I80
J 0
(-100 7875);
DISPLAY 0.978723 (-100 7875);
PAINT WHITE (-100 7875);
DISPLAY INVISIBLE (-100 7875);
FORCEPROP 1 LAST PART_NUMBER CS41002FB09
J 0
(-110 7575);
DISPLAY 0.510638 (-110 7575);
DISPLAY INVISIBLE (-110 7575);
FORCEADD MOSFET_NCH_DUAL..2
(-2425 7700);
FORCEPROP 1 LAST LOCATION Q67
J 0
(-2274 7676);
DISPLAY 0.723404 (-2274 7676);
PAINT GREEN (-2274 7676);
FORCEPROP 0 LAST $SEC 2
J 0
(-2250 7825);
DISPLAY 0.680851 (-2250 7825);
PAINT MONO (-2250 7825);
DISPLAY INVISIBLE (-2250 7825);
FORCEPROP 0 LAST CDS_SEC 2
J 0
(-2250 7825);
DISPLAY 1.021277 (-2250 7825);
DISPLAY INVISIBLE (-2250 7825);
FORCEPROP 0 LASTPIN (-2375 7900) $PN 3
R 1
J 0
(-2385 7910);
DISPLAY 0.680851 (-2385 7910);
PAINT MONO (-2385 7910);
FORCEPROP 0 LASTPIN (-2625 7650) $PN 5
J 2
(-2635 7660);
DISPLAY 0.680851 (-2635 7660);
PAINT MONO (-2635 7660);
FORCEPROP 0 LASTPIN (-2375 7500) $PN 4
R 1
J 2
(-2385 7490);
DISPLAY 0.680851 (-2385 7490);
PAINT MONO (-2385 7490);
FORCEPROP 1 LAST MATERIAL IC
J 0
(-2274 7551);
DISPLAY 0.723404 (-2274 7551);
PAINT GREEN (-2274 7551);
FORCEPROP 2 LAST PART_TYPE SMLF
J 0
(-2250 7775);
DISPLAY 1.021277 (-2250 7775);
FORCEPROP 2 LAST VALUE PJT138K
J 0
(-2250 7725);
DISPLAY 1.021277 (-2250 7725);
FORCEPROP 1 LAST CDS_LMAN_SYM_OUTLINE -150,150,150,-150
J 0
(-2425 7700);
DISPLAY 0.468085 (-2425 7700);
PAINT GREEN (-2425 7700);
DISPLAY INVISIBLE (-2425 7700);
FORCEPROP 1 LAST NEEDS_NO_SIZE TRUE
J 0
(-2275 7591);
DISPLAY 0.468085 (-2275 7591);
PAINT GREEN (-2275 7591);
DISPLAY INVISIBLE (-2275 7591);
FORCEPROP 2 LAST CDS_LIB pure_quanta
J 0
(-2425 7700);
DISPLAY INVISIBLE (-2425 7700);
FORCEPROP 1 LAST PATH I82
J 0
(-2275 7550);
DISPLAY 0.723404 (-2275 7550);
PAINT GREEN (-2275 7550);
DISPLAY INVISIBLE (-2275 7550);
FORCEPROP 1 LAST PART_NUMBER BAM138K0003
J 0
(-2274 7606);
DISPLAY 0.723404 (-2274 7606);
PAINT GREEN (-2274 7606);
DISPLAY INVISIBLE (-2274 7606);
FORCEADD UNIVERSAL_GND..1
(-2375 7325);
FORCEPROP 3 LASTPIN (-2375 7375) SIG_NAME GND\g
J 0
(-2365 7385);
DISPLAY 0.659574 (-2365 7385);
PAINT MONO (-2365 7385);
DISPLAY INVISIBLE (-2365 7385);
FORCEPROP 2 LAST CDS_LIB pure_quanta_power
J 0
(-2375 7325);
DISPLAY INVISIBLE (-2375 7325);
FORCEPROP 1 LAST HDL_POWER GND
J 1
(-2350 7250);
DISPLAY 0.872340 (-2350 7250);
PAINT GREEN (-2350 7250);
DISPLAY INVISIBLE (-2350 7250);
FORCEPROP 1 LAST PATH I83
J 0
(-2300 7325);
DISPLAY 0.872340 (-2300 7325);
PAINT AQUA (-2300 7325);
DISPLAY INVISIBLE (-2300 7325);
FORCEADD UNIVERSAL_POWER..1
(-2375 8350);
FORCEPROP 3 LASTPIN (-2375 8300) SIG_NAME P3V3_AUX\g
J 0
(-2365 8310);
DISPLAY 0.659574 (-2365 8310);
PAINT MONO (-2365 8310);
DISPLAY INVISIBLE (-2365 8310);
FORCEPROP 1 LAST HDL_POWER P3V3_AUX
J 1
(-2375 8400);
DISPLAY 0.872340 (-2375 8400);
PAINT GREEN (-2375 8400);
FORCEPROP 2 LAST CDS_LIB pure_quanta_power
J 0
(-2375 8350);
PAINT MONO (-2375 8350);
DISPLAY INVISIBLE (-2375 8350);
FORCEPROP 1 LAST PATH I85
J 0
(-2325 8375);
DISPLAY 0.872340 (-2325 8375);
PAINT AQUA (-2325 8375);
DISPLAY INVISIBLE (-2325 8375);
FORCEADD OFFPAGE..2
(-1425 7900);
FORCEPROP 2 LAST $XR0 81 
J 0
(-1236 7900);
DISPLAY 0.638298 (-1236 7900);
PAINT MONO (-1236 7900);
FORCEPROP 2 LAST CDS_LIB standard
J 0
(-1425 7900);
DISPLAY INVISIBLE (-1425 7900);
FORCEPROP 1 LAST OFFPAGE TRUE
J 0
(-1100 7775);
DISPLAY 0.872340 (-1100 7775);
PAINT AQUA (-1100 7775);
DISPLAY INVISIBLE (-1100 7775);
FORCEPROP 1 LAST COMMENT_BODY TRUE
J 0
(-1470 7805);
DISPLAY 0.872340 (-1470 7805);
PAINT GREEN (-1470 7805);
DISPLAY INVISIBLE (-1470 7805);
FORCEPROP 2 LAST PATH I86
J 0
(-1250 7975);
DISPLAY 1.021277 (-1250 7975);
DISPLAY INVISIBLE (-1250 7975);
FORCEADD OFFPAGE..2
(-1450 6525);
FORCEPROP 2 LAST $XR0 81 
J 0
(-1261 6525);
DISPLAY 0.638298 (-1261 6525);
PAINT MONO (-1261 6525);
FORCEPROP 2 LAST CDS_LIB standard
J 0
(-1450 6525);
DISPLAY INVISIBLE (-1450 6525);
FORCEPROP 1 LAST OFFPAGE TRUE
J 0
(-1125 6400);
DISPLAY 0.872340 (-1125 6400);
PAINT AQUA (-1125 6400);
DISPLAY INVISIBLE (-1125 6400);
FORCEPROP 1 LAST COMMENT_BODY TRUE
J 0
(-1495 6430);
DISPLAY 0.872340 (-1495 6430);
PAINT GREEN (-1495 6430);
DISPLAY INVISIBLE (-1495 6430);
FORCEPROP 2 LAST PATH I87
J 0
(-1250 6575);
DISPLAY 1.021277 (-1250 6575);
DISPLAY INVISIBLE (-1250 6575);
FORCEADD MOSFET_NCH_DUAL..2
(-2525 6300);
FORCEPROP 1 LAST LOCATION Q69
J 0
(-2374 6276);
DISPLAY 0.723404 (-2374 6276);
PAINT GREEN (-2374 6276);
FORCEPROP 0 LAST $SEC 2
J 0
(-2350 6425);
DISPLAY 0.680851 (-2350 6425);
PAINT MONO (-2350 6425);
DISPLAY INVISIBLE (-2350 6425);
FORCEPROP 0 LAST CDS_SEC 2
J 0
(-2350 6425);
DISPLAY 1.021277 (-2350 6425);
DISPLAY INVISIBLE (-2350 6425);
FORCEPROP 0 LASTPIN (-2475 6500) $PN 3
R 1
J 0
(-2485 6510);
DISPLAY 0.680851 (-2485 6510);
PAINT MONO (-2485 6510);
FORCEPROP 0 LASTPIN (-2725 6250) $PN 5
J 2
(-2735 6260);
DISPLAY 0.680851 (-2735 6260);
PAINT MONO (-2735 6260);
FORCEPROP 0 LASTPIN (-2475 6100) $PN 4
R 1
J 2
(-2485 6090);
DISPLAY 0.680851 (-2485 6090);
PAINT MONO (-2485 6090);
FORCEPROP 2 LAST PART_TYPE SMLF
J 0
(-2350 6375);
DISPLAY 1.021277 (-2350 6375);
FORCEPROP 2 LAST VALUE PJT138K
J 0
(-2350 6325);
DISPLAY 1.021277 (-2350 6325);
FORCEPROP 1 LAST MATERIAL IC
J 0
(-2374 6151);
DISPLAY 0.723404 (-2374 6151);
PAINT GREEN (-2374 6151);
FORCEPROP 1 LAST CDS_LMAN_SYM_OUTLINE -150,150,150,-150
J 0
(-2525 6300);
DISPLAY 0.468085 (-2525 6300);
PAINT GREEN (-2525 6300);
DISPLAY INVISIBLE (-2525 6300);
FORCEPROP 1 LAST NEEDS_NO_SIZE TRUE
J 0
(-2375 6191);
DISPLAY 0.468085 (-2375 6191);
PAINT GREEN (-2375 6191);
DISPLAY INVISIBLE (-2375 6191);
FORCEPROP 2 LAST CDS_LIB pure_quanta
J 0
(-2525 6300);
DISPLAY INVISIBLE (-2525 6300);
FORCEPROP 1 LAST PATH I88
J 0
(-2375 6150);
DISPLAY 0.723404 (-2375 6150);
PAINT GREEN (-2375 6150);
DISPLAY INVISIBLE (-2375 6150);
FORCEPROP 1 LAST PART_NUMBER BAM138K0003
J 0
(-2374 6206);
DISPLAY 0.723404 (-2374 6206);
PAINT GREEN (-2374 6206);
DISPLAY INVISIBLE (-2374 6206);
FORCEADD UNIVERSAL_GND..1
(-2475 5925);
FORCEPROP 3 LASTPIN (-2475 5975) SIG_NAME GND\g
J 0
(-2465 5985);
DISPLAY 0.659574 (-2465 5985);
PAINT MONO (-2465 5985);
DISPLAY INVISIBLE (-2465 5985);
FORCEPROP 2 LAST CDS_LIB pure_quanta_power
J 0
(-2475 5925);
DISPLAY INVISIBLE (-2475 5925);
FORCEPROP 1 LAST HDL_POWER GND
J 1
(-2450 5850);
DISPLAY 0.872340 (-2450 5850);
PAINT GREEN (-2450 5850);
DISPLAY INVISIBLE (-2450 5850);
FORCEPROP 1 LAST PATH I89
J 0
(-2400 5925);
DISPLAY 0.872340 (-2400 5925);
PAINT AQUA (-2400 5925);
DISPLAY INVISIBLE (-2400 5925);
FORCEADD UNIVERSAL_POWER..1
(-2475 6950);
FORCEPROP 3 LASTPIN (-2475 6900) SIG_NAME P3V3_AUX\g
J 0
(-2465 6910);
DISPLAY 0.659574 (-2465 6910);
PAINT MONO (-2465 6910);
DISPLAY INVISIBLE (-2465 6910);
FORCEPROP 1 LAST HDL_POWER P3V3_AUX
J 1
(-2475 7000);
DISPLAY 0.872340 (-2475 7000);
PAINT GREEN (-2475 7000);
FORCEPROP 2 LAST CDS_LIB pure_quanta_power
J 0
(-2475 6950);
PAINT MONO (-2475 6950);
DISPLAY INVISIBLE (-2475 6950);
FORCEPROP 1 LAST PATH I90
J 0
(-2425 6975);
DISPLAY 0.872340 (-2425 6975);
PAINT AQUA (-2425 6975);
DISPLAY INVISIBLE (-2425 6975);
FORCEADD Q_RES..2
(-2475 6725);
FORCEPROP 1 LAST LOCATION R2919
J 0
(-2430 6850);
DISPLAY 0.638298 (-2430 6850);
FORCEPROP 2 LAST $SEC 1
J 0
(-2425 6950);
DISPLAY 0.680851 (-2425 6950);
PAINT MONO (-2425 6950);
DISPLAY INVISIBLE (-2425 6950);
FORCEPROP 2 LAST CDS_SEC 1
J 0
(-2425 6950);
DISPLAY 1.021277 (-2425 6950);
DISPLAY INVISIBLE (-2425 6950);
FORCEPROP 1 LASTPIN (-2475 6825) $PN 1
J 0
(-2470 6787);
DISPLAY 0.787234 (-2470 6787);
FORCEPROP 1 LASTPIN (-2475 6625) $PN 2
J 0
(-2470 6635);
DISPLAY 0.787234 (-2470 6635);
FORCEPROP 1 LAST PACK_TYPE 0402LF
J 0
(-2435 6600);
DISPLAY 0.638298 (-2435 6600);
FORCEPROP 1 LAST MATERIAL CHIP
J 0
(-2435 6650);
DISPLAY 0.638298 (-2435 6650);
FORCEPROP 1 LAST WATTAGE 1/16W
J 0
(-2435 6700);
DISPLAY 0.638298 (-2435 6700);
FORCEPROP 1 LAST VALUE 100K
J 0
(-2430 6800);
DISPLAY 0.638298 (-2430 6800);
FORCEPROP 1 LAST TOLERANCE 1%
J 0
(-2430 6750);
DISPLAY 0.638298 (-2430 6750);
FORCEPROP 2 LAST CDS_LIB pure_quanta
J 0
(-2475 6725);
PAINT MONO (-2475 6725);
DISPLAY INVISIBLE (-2475 6725);
FORCEPROP 1 LAST PATH I91
J 0
(-2425 6900);
DISPLAY 0.978723 (-2425 6900);
PAINT WHITE (-2425 6900);
DISPLAY INVISIBLE (-2425 6900);
FORCEPROP 1 LAST PART_NUMBER CS41002FB09
J 0
(-2435 6550);
DISPLAY 0.638298 (-2435 6550);
DISPLAY INVISIBLE (-2435 6550);
FORCEADD Q_CAP..1
(-1600 4925);
FORCEPROP 1 LAST LOCATION C1754
J 0
(-1550 5025);
DISPLAY 0.638298 (-1550 5025);
FORCEPROP 2 LAST $SEC 1
J 0
(-1550 5125);
DISPLAY 0.680851 (-1550 5125);
PAINT MONO (-1550 5125);
DISPLAY INVISIBLE (-1550 5125);
FORCEPROP 2 LAST CDS_SEC 1
J 0
(-1550 5125);
DISPLAY 1.021277 (-1550 5125);
DISPLAY INVISIBLE (-1550 5125);
FORCEPROP 1 LASTPIN (-1600 5025) $PN 1
J 0
(-1590 5005);
DISPLAY 0.787234 (-1590 5005);
PAINT MONO (-1590 5005);
FORCEPROP 1 LASTPIN (-1600 4825) $PN 2
J 0
(-1590 4805);
DISPLAY 0.787234 (-1590 4805);
PAINT MONO (-1590 4805);
FORCEPROP 1 LAST VALUE 0.1UF
J 0
(-1550 4975);
DISPLAY 0.638298 (-1550 4975);
FORCEPROP 1 LAST TOLERANCE 10%
J 0
(-1550 4875);
DISPLAY 0.638298 (-1550 4875);
FORCEPROP 1 LAST MATERIAL X7R
J 0
(-1550 4825);
DISPLAY 0.638298 (-1550 4825);
PAINT RED (-1550 4825);
FORCEPROP 1 LAST PACK_TYPE 0402
J 0
(-1550 4725);
DISPLAY 0.638298 (-1550 4725);
FORCEPROP 1 LAST VOLTAGE 25V
J 0
(-1550 4925);
DISPLAY 0.638298 (-1550 4925);
FORCEPROP 2 LAST CDS_LIB pure_quanta
J 0
(-1600 4925);
DISPLAY INVISIBLE (-1600 4925);
FORCEPROP 1 LAST PATH I92
J 0
(-1550 5075);
DISPLAY 0.978723 (-1550 5075);
PAINT WHITE (-1550 5075);
DISPLAY INVISIBLE (-1550 5075);
FORCEPROP 1 LAST PART_NUMBER CH4104K1B00
J 0
(-1550 4775);
DISPLAY 0.638298 (-1550 4775);
DISPLAY INVISIBLE (-1550 4775);
FORCEADD UNIVERSAL_GND..1
(-1600 4725);
FORCEPROP 3 LASTPIN (-1600 4775) SIG_NAME GND\g
J 0
(-1590 4785);
DISPLAY 0.659574 (-1590 4785);
PAINT MONO (-1590 4785);
DISPLAY INVISIBLE (-1590 4785);
FORCEPROP 2 LAST CDS_LIB pure_quanta_power
J 0
(-1600 4725);
DISPLAY INVISIBLE (-1600 4725);
FORCEPROP 1 LAST HDL_POWER GND
J 1
(-1575 4650);
DISPLAY 0.872340 (-1575 4650);
PAINT GREEN (-1575 4650);
DISPLAY INVISIBLE (-1575 4650);
FORCEPROP 1 LAST PATH I93
J 0
(-1525 4725);
DISPLAY 0.872340 (-1525 4725);
PAINT AQUA (-1525 4725);
DISPLAY INVISIBLE (-1525 4725);
FORCEADD OFFPAGE..2
(-1350 5175);
FORCEPROP 2 LAST $XR0 81 
J 0
(-1161 5175);
DISPLAY 0.638298 (-1161 5175);
PAINT MONO (-1161 5175);
FORCEPROP 2 LAST CDS_LIB standard
J 0
(-1350 5175);
DISPLAY INVISIBLE (-1350 5175);
FORCEPROP 1 LAST OFFPAGE TRUE
J 0
(-1025 5050);
DISPLAY 0.872340 (-1025 5050);
PAINT AQUA (-1025 5050);
DISPLAY INVISIBLE (-1025 5050);
FORCEPROP 1 LAST COMMENT_BODY TRUE
J 0
(-1395 5080);
DISPLAY 0.872340 (-1395 5080);
PAINT GREEN (-1395 5080);
DISPLAY INVISIBLE (-1395 5080);
FORCEPROP 2 LAST PATH I94
J 0
(-1150 5225);
DISPLAY 1.021277 (-1150 5225);
DISPLAY INVISIBLE (-1150 5225);
FORCEADD UNIVERSAL_GND..1
(-2500 4550);
FORCEPROP 3 LASTPIN (-2500 4600) SIG_NAME GND\g
J 0
(-2490 4610);
DISPLAY 0.659574 (-2490 4610);
PAINT MONO (-2490 4610);
DISPLAY INVISIBLE (-2490 4610);
FORCEPROP 2 LAST CDS_LIB pure_quanta_power
J 0
(-2500 4550);
DISPLAY INVISIBLE (-2500 4550);
FORCEPROP 1 LAST HDL_POWER GND
J 1
(-2475 4475);
DISPLAY 0.872340 (-2475 4475);
PAINT GREEN (-2475 4475);
DISPLAY INVISIBLE (-2475 4475);
FORCEPROP 1 LAST PATH I96
J 0
(-2425 4550);
DISPLAY 0.872340 (-2425 4550);
PAINT AQUA (-2425 4550);
DISPLAY INVISIBLE (-2425 4550);
FORCEADD UNIVERSAL_POWER..1
(-2500 5650);
FORCEPROP 3 LASTPIN (-2500 5600) SIG_NAME P3V3_AUX\g
J 0
(-2490 5610);
DISPLAY 0.659574 (-2490 5610);
PAINT MONO (-2490 5610);
DISPLAY INVISIBLE (-2490 5610);
FORCEPROP 1 LAST HDL_POWER P3V3_AUX
J 1
(-2500 5700);
DISPLAY 0.872340 (-2500 5700);
PAINT GREEN (-2500 5700);
FORCEPROP 2 LAST CDS_LIB pure_quanta_power
J 0
(-2500 5650);
DISPLAY INVISIBLE (-2500 5650);
FORCEPROP 1 LAST PATH I98
J 0
(-2450 5675);
DISPLAY 0.872340 (-2450 5675);
PAINT AQUA (-2450 5675);
DISPLAY INVISIBLE (-2450 5675);
FORCEADD OFFPAGE..2
(3075 8025);
FORCEPROP 2 LAST $XR0 81 
J 0
(3264 8025);
DISPLAY 0.638298 (3264 8025);
PAINT MONO (3264 8025);
FORCEPROP 2 LAST CDS_LIB standard
J 0
(3075 8025);
DISPLAY INVISIBLE (3075 8025);
FORCEPROP 1 LAST OFFPAGE TRUE
J 0
(3400 7900);
DISPLAY 0.872340 (3400 7900);
PAINT AQUA (3400 7900);
DISPLAY INVISIBLE (3400 7900);
FORCEPROP 1 LAST COMMENT_BODY TRUE
J 0
(3030 7930);
DISPLAY 0.872340 (3030 7930);
PAINT GREEN (3030 7930);
DISPLAY INVISIBLE (3030 7930);
FORCEPROP 2 LAST PATH I99
J 0
(3275 8075);
DISPLAY 1.021277 (3275 8075);
DISPLAY INVISIBLE (3275 8075);
FORCEADD DNS..2
(-100 4500);
PAINT RED (-100 4500);
FORCEPROP 2 LAST CDS_LIB mstr_misc
J 0
(-100 4500);
DISPLAY INVISIBLE (-100 4500);
FORCEPROP 1 LAST COMMENT_BODY TRUE
J 0
(-100 4500);
DISPLAY INVISIBLE (-100 4500);
FORCEADD DNS..2
(-175 3375);
PAINT RED (-175 3375);
FORCEPROP 2 LAST CDS_LIB mstr_misc
J 0
(-175 3375);
DISPLAY INVISIBLE (-175 3375);
FORCEPROP 1 LAST COMMENT_BODY TRUE
J 0
(-175 3375);
DISPLAY INVISIBLE (-175 3375);
FORCEADD DNS..2
(-4650 2800);
PAINT RED (-4650 2800);
FORCEPROP 2 LAST CDS_LIB mstr_misc
J 0
(-4650 2800);
DISPLAY INVISIBLE (-4650 2800);
FORCEPROP 1 LAST COMMENT_BODY TRUE
J 0
(-4650 2800);
DISPLAY INVISIBLE (-4650 2800);
FORCEADD DNS..2
(-4675 7125);
PAINT RED (-4675 7125);
FORCEPROP 2 LAST CDS_LIB mstr_misc
J 0
(-4675 7125);
DISPLAY INVISIBLE (-4675 7125);
FORCEPROP 1 LAST COMMENT_BODY TRUE
J 0
(-4675 7125);
DISPLAY INVISIBLE (-4675 7125);
FORCEADD DNS..2
(-4650 5725);
PAINT RED (-4650 5725);
FORCEPROP 2 LAST CDS_LIB mstr_misc
J 0
(-4650 5725);
DISPLAY INVISIBLE (-4650 5725);
FORCEPROP 1 LAST COMMENT_BODY TRUE
J 0
(-4650 5725);
DISPLAY INVISIBLE (-4650 5725);
FORCEADD DNS..2
(-4600 4375);
PAINT RED (-4600 4375);
FORCEPROP 2 LAST CDS_LIB mstr_misc
J 0
(-4600 4375);
DISPLAY INVISIBLE (-4600 4375);
FORCEPROP 1 LAST COMMENT_BODY TRUE
J 0
(-4600 4375);
DISPLAY INVISIBLE (-4600 4375);
FORCEADD DNS..2
(-150 7675);
PAINT RED (-150 7675);
FORCEPROP 2 LAST CDS_LIB mstr_misc
J 0
(-150 7675);
DISPLAY INVISIBLE (-150 7675);
FORCEPROP 1 LAST COMMENT_BODY TRUE
J 0
(-150 7675);
DISPLAY INVISIBLE (-150 7675);
FORCEADD DNS..2
(-150 6300);
PAINT RED (-150 6300);
FORCEPROP 2 LAST CDS_LIB mstr_misc
J 0
(-150 6300);
DISPLAY INVISIBLE (-150 6300);
FORCEPROP 1 LAST COMMENT_BODY TRUE
J 0
(-150 6300);
DISPLAY INVISIBLE (-150 6300);
FORCEADD QUANTA_TITLE_BLOCK_C..1
(3750 2300);
FORCEPROP 0 LAST CDS_CON_LAST_MODIFIED Thu Sep 14 16:12:23 2023
J 0
(1865 2315);
PAINT MONO (1865 2315);
DISPLAY INVISIBLE (1865 2315);
FORCEPROP 1 LAST CUSTOM_TXT_CDS <CON_LAST_MODIFIED>
J 0
(1865 2315);
DISPLAY 0.978723 (1865 2315);
FORCEPROP 2 LAST CUSTOM_TXT_CDS <XR_PAGE_TITLE>
J 0
(-4140 7550);
DISPLAY 0.638298 (-4140 7550);
PAINT PINK (-4140 7550);
DISPLAY INVISIBLE (-4140 7550);
FORCEPROP 2 LAST CUSTOM_TXT_CDS <Q_NUMBER>
J 0
(2347 2403);
DISPLAY 1.212766 (2347 2403);
FORCEPROP 2 LAST CUSTOM_TXT_CDS <Q_REV>
J 0
(3566 2403);
DISPLAY 1.212766 (3566 2403);
FORCEPROP 2 LAST CUSTOM_TXT_CDS <CON_PAGE_NUM> OF <CON_TOTAL_PAGES>
J 0
(3304 2318);
DISPLAY 0.978723 (3304 2318);
FORCEPROP 2 LAST CUSTOM_TXT_CDS <Q_PROJ>
J 0
(1368 2402);
DISPLAY 1.212766 (1368 2402);
FORCEPROP 2 LAST CUSTOM_TXT_CDS <NAME_2>
J 0
(575 2350);
FORCEPROP 2 LAST CUSTOM_TXT_CDS <NAME_1>
J 0
(575 2475);
FORCEPROP 1 LAST Q_TITLE EXAMAX_ISO (4/7)
J 0
(-5525 2350);
DISPLAY 1.957447 (-5525 2350);
PAINT GREEN (-5525 2350);
FORCEPROP 2 LAST CDS_LIB pure_quanta
J 0
(3750 2300);
PAINT MONO (3750 2300);
DISPLAY INVISIBLE (3750 2300);
FORCEPROP 1 LAST CDS_LMAN_SYM_OUTLINE -9475,6775,100,-125
J 0
(3750 2300);
DISPLAY 0.468085 (3750 2300);
PAINT GREEN (3750 2300);
DISPLAY INVISIBLE (3750 2300);
FORCEPROP 2 LAST PAGE_BORDER TRUE
J 0
(-4140 7550);
DISPLAY 0.638298 (-4140 7550);
PAINT PINK (-4140 7550);
DISPLAY INVISIBLE (-4140 7550);
FORCEPROP 2 LAST CDS_XR_PAGE_TITLE CR-127 : @T6G_MB_LIB.T6G(SCH_1):PAGE127
J 0
(-4140 7550);
DISPLAY 0.638298 (-4140 7550);
PAINT PINK (-4140 7550);
DISPLAY INVISIBLE (-4140 7550);
FORCEPROP 1 LAST Q_DEPT BU9
J 1
(-13 2349);
DISPLAY 1.957447 (-13 2349);
PAINT GREEN (-13 2349);
DISPLAY INVISIBLE (-13 2349);
FORCEPROP 1 LAST COMMENT_BODY TRUE
J 0
(3762 2287);
DISPLAY 0.978723 (3762 2287);
PAINT GREEN (3762 2287);
DISPLAY INVISIBLE (3762 2287);
WIRE 16 -1 (-3525 7200)(-3525 7075);
WIRE 16 -1 (1925 8425)(1925 8275);
WIRE 16 -1 (1925 7600)(1925 7475);
WIRE 16 -1 (2925 6150)(2925 6100);
WIRE 16 -1 (2025 6225)(2025 6100);
WIRE 16 -1 (-3475 5800)(-3475 5675);
WIRE 16 -1 (2025 7125)(2025 6975);
WIRE 16 -1 (2875 7675)(2875 7625);
WIRE 16 -1 (-1600 7550)(-1600 7500);
WIRE 16 -1 (-1650 6175)(-1650 6125);
WIRE 16 -1 (-3450 4450)(-3450 4325);
WIRE 16 -1 (2050 5750)(2050 5600);
WIRE 16 -1 (2950 4775)(2950 4725);
WIRE 16 -1 (1125 5500)(1125 5350);
WIRE 16 -1 (-3525 8175)(-3525 8100);
WIRE 16 -1 (2050 4850)(2050 4725);
WIRE 16 -1 (1125 4575)(1125 4450);
WIRE 16 -1 (-125 5200)(-125 5050);
WIRE 16 -1 (-100 4375)(-100 4425);
WIRE 16 -1 (-4650 2675)(-4650 2725);
WIRE 16 -1 (-4675 3500)(-4675 3350);
WIRE 16 -1 (-3425 2875)(-3425 2750);
WIRE 16 -1 (-2500 3150)(-2500 3025);
WIRE 16 -1 (-3425 3800)(-3425 3650);
WIRE 16 -1 (-1600 3075)(-1600 3025);
WIRE 16 -1 (-2500 4050)(-2500 3900);
WIRE 16 -1 (2000 4200)(2000 4050);
WIRE 16 -1 (2900 3225)(2900 3175);
WIRE 16 -1 (-3475 6700)(-3475 6550);
WIRE 16 -1 (2000 3300)(2000 3175);
WIRE 16 -1 (1075 3950)(1075 3800);
WIRE 16 -1 (1075 3025)(1075 2900);
WIRE 16 -1 (-175 3650)(-175 3500);
WIRE 16 -1 (-150 2825)(-150 2875);
WIRE 16 -1 (-3450 5350)(-3450 5200);
WIRE 16 -1 (1100 7325)(1100 7200);
WIRE 16 -1 (1100 8175)(1100 8025);
WIRE 16 -1 (1100 5950)(1100 5825);
WIRE 16 -1 (1100 6875)(1100 6725);
WIRE 16 -1 (-4700 7825)(-4700 7725);
WIRE 16 -1 (-4675 6425)(-4675 6325);
WIRE 16 -1 (-4625 5075)(-4625 4975);
WIRE 16 -1 (-150 7950)(-150 7800);
WIRE 16 -1 (-150 6575)(-150 6425);
WIRE 16 -1 (-4675 7000)(-4675 7050);
WIRE 16 -1 (-4650 5625)(-4650 5650);
WIRE 16 -1 (-4600 4275)(-4600 4300);
WIRE 16 -1 (-125 7150)(-125 7175);
WIRE 16 -1 (-125 5750)(-125 5800);
WIRE 16 -1 (-2375 7500)(-2375 7375);
WIRE 16 -1 (-2375 8300)(-2375 8225);
WIRE 16 -1 (-2475 6100)(-2475 5975);
WIRE 16 -1 (-2475 6900)(-2475 6825);
WIRE 16 -1 (-1600 4825)(-1600 4775);
WIRE 16 -1 (-2500 4725)(-2500 4600);
WIRE 16 -1 (-2500 5600)(-2500 5450);
WIRE 16 -1 (-150 6225)(-150 6100);
WIRE 16 -1 (-125 6100)(-150 6100);
WIRE 16 -1 (-150 6100)(-375 6100);
WIRE 16 -1 (850 6100)(-125 6100);
FORCEPROP 2 LAST SIG_NAME FM_GPU_PWRGD
J 0
(190 6110);
DISPLAY 0.808511 (190 6110);
WIRE 16 -1 (-125 6000)(-125 6100);
WIRE 16 -1 (850 7475)(-125 7475);
FORCEPROP 2 LAST SIG_NAME FM_SWB_PWRGD
J 0
(190 7485);
DISPLAY 0.808511 (190 7485);
WIRE 16 -1 (-125 7475)(-150 7475);
WIRE 16 -1 (-125 7375)(-125 7475);
WIRE 16 -1 (-150 7600)(-150 7475);
WIRE 16 -1 (-150 7475)(-375 7475);
WIRE 16 -1 (-2500 5125)(-2500 5175);
WIRE 16 -1 (-1600 5175)(-2500 5175);
FORCEPROP 2 LAST SIG_NAME FM_SWB_BIC_READY_ISO_N
J 0
(-2360 5185);
DISPLAY 0.808511 (-2360 5185);
WIRE 16 -1 (-2500 5250)(-2500 5175);
WIRE 16 -1 (-1400 5175)(-1600 5175);
WIRE 16 -1 (-1600 5175)(-1600 5025);
WIRE 16 -1 (-2475 6500)(-2475 6525);
WIRE 16 -1 (-1650 6525)(-2475 6525);
FORCEPROP 2 LAST SIG_NAME RST_BMC_FROM_SWB_ISO_N
J 0
(-2385 6535);
DISPLAY 0.808511 (-2385 6535);
WIRE 16 -1 (-2475 6625)(-2475 6525);
WIRE 16 -1 (-1500 6525)(-1650 6525);
WIRE 16 -1 (-1650 6525)(-1650 6375);
WIRE 16 -1 (3125 3725)(2900 3725);
WIRE 16 -1 (2900 3725)(2900 3425);
WIRE 16 -1 (2900 3725)(2000 3725);
FORCEPROP 2 LAST SIG_NAME GPU_FPGA_READY_ISO
J 0
(2090 3735);
DISPLAY 0.808511 (2090 3735);
WIRE 16 -1 (2000 3850)(2000 3725);
WIRE 16 -1 (2000 3725)(2000 3700);
WIRE 16 -1 (3025 8025)(2875 8025);
WIRE 16 -1 (2875 8025)(2875 7875);
WIRE 16 -1 (2875 8025)(1925 8025);
FORCEPROP 2 LAST SIG_NAME FM_SWB_PWRGD_ISO
J 0
(2390 8035);
DISPLAY 0.808511 (2390 8035);
WIRE 16 -1 (1925 8025)(1925 8000);
WIRE 16 -1 (1925 8075)(1925 8025);
WIRE 16 -1 (3175 5275)(2950 5275);
WIRE 16 -1 (2950 5275)(2050 5275);
FORCEPROP 2 LAST SIG_NAME FM_SMB_2_ALERT_GPU_ISO_N
J 0
(2140 5285);
DISPLAY 0.808511 (2140 5285);
WIRE 16 -1 (2950 5275)(2950 4975);
WIRE 16 -1 (2050 5400)(2050 5275);
WIRE 16 -1 (2050 5275)(2050 5250);
WIRE 16 -1 (-2375 8025)(-2375 7900);
WIRE 16 -1 (-1600 7900)(-2375 7900);
FORCEPROP 2 LAST SIG_NAME BIC_MONITER_ISO
J 0
(-2310 7910);
DISPLAY 0.808511 (-2310 7910);
WIRE 16 -1 (-1475 7900)(-1600 7900);
WIRE 16 -1 (-1600 7900)(-1600 7750);
WIRE 16 -1 (-1375 3575)(-1600 3575);
WIRE 16 -1 (-1600 3575)(-1600 3275);
WIRE 16 -1 (-1600 3575)(-2500 3575);
FORCEPROP 2 LAST SIG_NAME FM_SMB_1_ALERT_GPU_ISO_N
J 0
(-2410 3585);
DISPLAY 0.808511 (-2410 3585);
WIRE 16 -1 (-2500 3700)(-2500 3575);
WIRE 16 -1 (-2500 3575)(-2500 3550);
WIRE 16 -1 (3150 6650)(2925 6650);
WIRE 16 -1 (2925 6650)(2925 6350);
WIRE 16 -1 (2925 6650)(2025 6650);
FORCEPROP 2 LAST SIG_NAME FM_GPU_PWRGD_ISO
J 0
(2115 6660);
DISPLAY 0.808511 (2115 6660);
WIRE 16 -1 (2025 6775)(2025 6650);
WIRE 16 -1 (2025 6650)(2025 6625);
WIRE 16 -1 (-3700 4600)(-4600 4600);
FORCEPROP 2 LAST SIG_NAME FM_SWB_BIC_READY_N
J 0
(-4435 4610);
DISPLAY 0.808511 (-4435 4610);
WIRE 16 -1 (-4600 4500)(-4600 4600);
WIRE 16 -1 (-4600 4600)(-4625 4600);
WIRE 16 -1 (-4625 4775)(-4625 4600);
WIRE 16 -1 (-4625 4600)(-4825 4600);
WIRE 16 -1 (-2750 4875)(-3450 4875);
FORCEPROP 2 LAST SIG_NAME FM_SWB_BIC_READY
J 0
(-3410 4885);
DISPLAY 0.808511 (-3410 4885);
FORCEPROP 2 LASTPROP $XRERR UNIQUE?
J 0
(-3650 4885);
DISPLAY 0.638298 (-3650 4885);
PAINT MONO (-3650 4885);
DISPLAY INVISIBLE (-3650 4885);
WIRE 16 -1 (-3450 5000)(-3450 4875);
WIRE 16 -1 (-3450 4875)(-3450 4850);
WIRE 16 -1 (-125 4850)(-125 4725);
WIRE 16 -1 (-100 4725)(-125 4725);
WIRE 16 -1 (-125 4725)(-350 4725);
WIRE 16 -1 (875 4725)(-100 4725);
FORCEPROP 2 LAST SIG_NAME FM_SMB_2_ALERT_GPU_N
J 0
(65 4735);
DISPLAY 0.808511 (65 4735);
WIRE 16 -1 (-100 4625)(-100 4725);
WIRE 16 -1 (-4675 6125)(-4675 5950);
WIRE 16 -1 (-4650 5950)(-4675 5950);
WIRE 16 -1 (-4675 5950)(-4825 5950);
WIRE 16 -1 (-3725 5950)(-4650 5950);
FORCEPROP 2 LAST SIG_NAME RST_BMC_FROM_SWB_N
J 0
(-4610 5960);
DISPLAY 0.808511 (-4610 5960);
WIRE 16 -1 (-4650 5850)(-4650 5950);
WIRE 16 -1 (-4700 7525)(-4700 7350);
WIRE 16 -1 (-4675 7350)(-4700 7350);
WIRE 16 -1 (-4700 7350)(-4900 7350);
WIRE 16 -1 (-3775 7350)(-4675 7350);
FORCEPROP 2 LAST SIG_NAME BIC_MONITER
J 0
(-4635 7360);
DISPLAY 0.808511 (-4635 7360);
WIRE 16 -1 (-4675 7250)(-4675 7350);
WIRE 16 -1 (-3475 6350)(-3475 6250);
WIRE 16 -1 (-2725 6250)(-3475 6250);
FORCEPROP 2 LAST SIG_NAME RST_BMC_FROM_SWB
J 0
(-3435 6260);
DISPLAY 0.808511 (-3435 6260);
FORCEPROP 2 LASTPROP $XRERR UNIQUE?
J 0
(-3675 6260);
DISPLAY 0.638298 (-3675 6260);
PAINT MONO (-3675 6260);
DISPLAY INVISIBLE (-3675 6260);
WIRE 16 -1 (-3475 6250)(-3475 6200);
WIRE 16 -1 (1100 7725)(1100 7750);
WIRE 16 -1 (1675 7750)(1100 7750);
FORCEPROP 2 LAST SIG_NAME FM_SWB_PWRGD_N
J 0
(1115 7760);
DISPLAY 0.808511 (1115 7760);
FORCEPROP 2 LASTPROP $XRERR UNIQUE?
J 0
(875 7760);
DISPLAY 0.638298 (875 7760);
PAINT MONO (875 7760);
DISPLAY INVISIBLE (875 7760);
WIRE 16 -1 (1100 7825)(1100 7750);
WIRE 16 -1 (1100 6350)(1100 6375);
WIRE 16 -1 (1775 6375)(1100 6375);
FORCEPROP 2 LAST SIG_NAME FM_GPU_PWRGD_N
J 0
(1190 6385);
DISPLAY 0.808511 (1190 6385);
FORCEPROP 2 LASTPROP $XRERR UNIQUE?
J 0
(950 6385);
DISPLAY 0.638298 (950 6385);
PAINT MONO (950 6385);
DISPLAY INVISIBLE (950 6385);
WIRE 16 -1 (1100 6525)(1100 6375);
WIRE 16 -1 (-3425 3275)(-3425 3300);
WIRE 16 -1 (-2750 3300)(-3425 3300);
FORCEPROP 2 LAST SIG_NAME FM_SMB_1_ALERT_GPU
J 0
(-3410 3310);
DISPLAY 0.808511 (-3410 3310);
FORCEPROP 2 LASTPROP $XRERR UNIQUE?
J 0
(-3650 3310);
DISPLAY 0.638298 (-3650 3310);
PAINT MONO (-3650 3310);
DISPLAY INVISIBLE (-3650 3310);
WIRE 16 -1 (-3425 3450)(-3425 3300);
WIRE 16 -1 (-4675 3150)(-4675 3025);
WIRE 16 -1 (-4650 3025)(-4675 3025);
WIRE 16 -1 (-4675 3025)(-4900 3025);
WIRE 16 -1 (-3675 3025)(-4650 3025);
FORCEPROP 2 LAST SIG_NAME FM_SMB_1_ALERT_GPU_N
J 0
(-4510 3035);
DISPLAY 0.808511 (-4510 3035);
WIRE 16 -1 (-4650 2925)(-4650 3025);
WIRE 16 -1 (1075 3425)(1075 3450);
WIRE 16 -1 (1600 3450)(1075 3450);
FORCEPROP 2 LAST SIG_NAME GPU_FPGA_READY_N
J 0
(1090 3460);
DISPLAY 0.808511 (1090 3460);
WIRE 16 -1 (1075 3600)(1075 3450);
WIRE 16 -1 (1750 3450)(1600 3450);
WIRE 16 -1 (1600 3450)(1600 2950);
WIRE 16 -1 (1600 2950)(2050 2950);
WIRE 16 -1 (-175 3300)(-175 3175);
WIRE 16 -1 (-150 3175)(-175 3175);
WIRE 16 -1 (-175 3175)(-400 3175);
WIRE 16 -1 (825 3175)(-150 3175);
FORCEPROP 2 LAST SIG_NAME GPU_FPGA_READY
J 0
(-10 3185);
DISPLAY 0.808511 (-10 3185);
WIRE 16 -1 (-150 3075)(-150 3175);
WIRE 16 -1 (-3525 7600)(-3525 7650);
WIRE 16 -1 (-2625 7650)(-3525 7650);
FORCEPROP 2 LAST SIG_NAME BIC_MONITER_N
J 0
(-3460 7660);
DISPLAY 0.808511 (-3460 7660);
FORCEPROP 2 LASTPROP $XRERR UNIQUE?
J 0
(-3700 7660);
DISPLAY 0.638298 (-3700 7660);
PAINT MONO (-3700 7660);
DISPLAY INVISIBLE (-3700 7660);
WIRE 16 -1 (-3525 7900)(-3525 7650);
WIRE 16 -1 (1125 4975)(1125 5000);
WIRE 16 -1 (1125 5150)(1125 5000);
WIRE 16 -1 (1800 5000)(1125 5000);
FORCEPROP 2 LAST SIG_NAME FM_SMB_2_ALERT_GPU
J 0
(1140 5010);
DISPLAY 0.808511 (1140 5010);
FORCEPROP 2 LASTPROP $XRERR UNIQUE?
J 0
(900 5010);
DISPLAY 0.638298 (900 5010);
PAINT MONO (900 5010);
DISPLAY INVISIBLE (900 5010);
DOT 1 (2050 5275);
DOT 1 (-2500 3575);
DOT 1 (-125 7475);
DOT 1 (-1600 3575);
DOT 1 (-3425 3300);
DOT 1 (1075 3450);
DOT 1 (2000 3725);
DOT 1 (2900 3725);
DOT 1 (-4700 7350);
DOT 1 (-3525 7650);
DOT 1 (-1600 7900);
DOT 1 (-3450 4875);
DOT 1 (2875 8025);
DOT 1 (1925 8025);
DOT 1 (2950 5275);
DOT 1 (-150 6100);
DOT 1 (1100 6375);
DOT 1 (2025 6650);
DOT 1 (2925 6650);
DOT 1 (1125 5000);
DOT 1 (-125 4725);
DOT 1 (-1650 6525);
DOT 1 (-4675 5950);
DOT 1 (-3475 6250);
DOT 1 (-2475 6525);
DOT 1 (-150 7475);
DOT 1 (1600 3450);
DOT 1 (1100 7750);
DOT 1 (-175 3175);
DOT 1 (-1600 5175);
DOT 1 (-4675 7350);
DOT 1 (-4650 5950);
DOT 1 (-150 3175);
DOT 1 (-100 4725);
DOT 1 (-125 6100);
DOT 1 (-4600 4600);
DOT 1 (-4625 4600);
DOT 1 (-2500 5175);
DOT 1 (-4650 3025);
DOT 1 (-4675 3025);
QUIT
